%FSTAX25Y25*%
%MOIN*%
%SFA1B1*%

%IPPOS*%
%AMD54*
4,1,8,0.010500,-0.010000,0.010500,0.010000,0.000000,0.020400,0.000000,0.020400,-0.010500,0.010000,-0.010500,-0.010000,0.000000,-0.020400,0.000000,-0.020400,0.010500,-0.010000,0.0*
1,1,0.020960,0.000000,-0.010000*
1,1,0.020960,0.000000,0.010000*
1,1,0.020960,0.000000,0.010000*
1,1,0.020960,0.000000,-0.010000*
%
%ADD23R,0.039370X0.027560*%
%ADD51R,0.026570X0.009840*%
%ADD52R,0.009840X0.026570*%
%ADD53R,0.019680X0.013780*%
G04~CAMADD=54~8~0.0~0.0~408.8~209.5~104.8~0.0~15~0.0~0.0~0.0~0.0~0~0.0~0.0~0.0~0.0~0~0.0~0.0~0.0~270.0~210.0~409.0*
%ADD54D54*%
%ADD55R,0.020950X0.040880*%
%ADD63R,0.314960X0.135830*%
%ADD64R,1.354330X0.230320*%
%ADD65R,0.049340X0.051310*%
%ADD66R,0.063120X0.063120*%
%ADD67R,0.047370X0.063120*%
%ADD68R,0.094610X0.049340*%
%ADD69R,0.049340X0.047370*%
%ADD70R,0.043430X0.027690*%
%ADD71R,0.085560X0.030440*%
%ADD72R,0.049340X0.033590*%
%ADD73R,0.058000X0.208000*%
%ADD74R,0.078870X0.017840*%
%ADD75R,0.065090X0.045400*%
%ADD76R,0.045400X0.039500*%
%ADD77R,0.045400X0.045400*%
%ADD78R,0.037530X0.041470*%
%ADD79R,0.043430X0.035560*%
%ADD80R,0.031620X0.039500*%
%ADD81R,0.047370X0.036350*%
%ADD82R,0.031620X0.033590*%
%ADD83R,0.036000X0.173000*%
%ADD84R,0.036000X0.134000*%
%ADD85O,0.094610X0.031620*%
%ADD86O,0.082800X0.031620*%
%ADD87R,0.220600X0.122170*%
%ADD88R,0.090870X0.052090*%
%ADD89R,0.017840X0.069020*%
%ADD90R,0.074930X0.061150*%
%ADD91R,0.061150X0.074930*%
%ADD92R,0.069020X0.017840*%
%ADD93R,0.041470X0.047370*%
%ADD94R,0.053280X0.065090*%
%ADD95R,0.045400X0.041470*%
%ADD96R,0.051310X0.049340*%
%ADD97R,0.045400X0.047370*%
%ADD98R,0.065090X0.053280*%
%ADD99R,0.036350X0.047370*%
%ADD100C,0.073980*%
%ADD101C,0.083000*%
%ADD102R,0.067060X0.067060*%
%ADD103C,0.067060*%
%ADD104C,0.008000*%
%ADD105C,0.029660*%
%ADD106R,0.008000X0.008000*%
%ADD107C,0.128000*%
%ADD108C,0.120000*%
%ADD109C,0.258000*%
%ADD110C,0.208000*%
%ADD111C,0.058000*%
%LNtimecard-dc-beta-v1-1*%
%LPD*%
G36*
X0679244Y0118147D02*
X0679295Y0118137D01*
X0679345Y011812*
X0679392Y0118097*
Y0118096*
X0679732*
X0679784Y0118093*
X0679836Y0118083*
X0679885Y0118066*
X0679932Y0118043*
X0679933Y0118042*
X0680002*
X0680055Y0118039*
X0680106Y0118029*
X0680156Y0118012*
X0680203Y0117989*
Y0117988*
X0680219*
X0680271Y0117985*
X0680322Y0117975*
X0680372Y0117958*
X0680419Y0117935*
X068045Y0117914*
X068048Y0117904*
X0680527Y011788*
X0680532Y0117877*
X0680541*
X0680593Y0117867*
X0680642Y011785*
X0680689Y0117826*
X068072Y0117806*
X0680751Y0117796*
X0680797Y0117772*
X0680802Y0117769*
X0680812*
X0680863Y0117758*
X0680913Y0117742*
X068096Y0117718*
X0681003Y0117689*
X0681043Y0117655*
X0681056Y011764*
X0681075Y0117633*
X0681122Y011761*
X0681153Y011759*
X0681183Y0117579*
X068123Y0117556*
X0681274Y0117527*
X0681313Y0117492*
X0681326Y0117478*
X0681345Y0117471*
X0681392Y0117448*
X0681436Y0117419*
X0681475Y0117384*
X0681488Y011737*
X0681507Y0117363*
X0681554Y011734*
X0681598Y0117311*
X0681637Y0117276*
X0681663Y0117247*
X0681692Y0117222*
X0681717Y0117193*
X0681746Y0117168*
X0681765Y0117146*
X0681771Y0117139*
X0681797Y0117117*
X06818Y0117114*
X0681825Y0117085*
X0681854Y011706*
X0681879Y0117031*
X0681908Y0117006*
X0681933Y0116977*
X0681962Y0116952*
X0681987Y0116923*
X0682016Y0116898*
X0682041Y0116869*
X068207Y0116844*
X0682095Y0116815*
X0682124Y011679*
X0682149Y0116761*
X0682178Y0116735*
X0682203Y0116707*
X0682232Y0116682*
X0682267Y0116642*
X0682296Y0116598*
X0682319Y0116551*
X0682326Y0116532*
X068234Y0116519*
X0682375Y011648*
X0682404Y0116436*
X0682427Y0116389*
X0682434Y011637*
X0682448Y0116357*
X0682483Y0116318*
X0682512Y0116274*
X0682535Y0116227*
X0682546Y0116197*
X0682566Y0116166*
X0682589Y0116119*
X0682596Y01161*
X0682611Y0116087*
X0682645Y0116047*
X0682674Y0116004*
X0682697Y0115957*
X0682708Y0115926*
X0682728Y0115896*
X0682752Y0115849*
X0682768Y0115799*
X0682779Y0115747*
Y0115738*
X0682782Y0115734*
X0682806Y0115686*
X0682816Y0115656*
X0682836Y0115625*
X068286Y0115578*
X0682876Y0115529*
X0682887Y0115477*
Y0115468*
X0682891Y0115463*
X0682914Y0115416*
X0682931Y0115366*
X0682941Y0115315*
X0682944Y0115263*
Y0115247*
X0682968Y01152*
X0682985Y011515*
X0682995Y0115099*
X0682998Y0115047*
Y0115031*
X0682999*
X0683022Y0114984*
X0683039Y0114934*
X0683049Y0114883*
X0683052Y011483*
Y0114776*
Y0114722*
Y0114668*
Y0114614*
Y011456*
Y0114506*
Y0114491*
X0683053Y011449*
X0683076Y0114443*
X0683093Y0114393*
X0683103Y0114342*
X0683106Y011429*
Y0114235*
Y0114181*
Y0114127*
Y0114073*
X0683103Y0114021*
X0683093Y011397*
X0683076Y011392*
X0683053Y0113873*
X0683052Y0113872*
Y0113857*
Y0113803*
Y0113749*
Y0113695*
Y0113641*
Y0113587*
X0683049Y0113534*
X0683039Y0113483*
X0683022Y0113433*
X0682999Y0113386*
X0682998*
Y0113371*
Y0113317*
X0682995Y0113264*
X0682985Y0113213*
X0682968Y0113163*
X0682944Y0113116*
X0682941Y0113111*
Y0113109*
Y0113102*
X0682931Y011305*
X0682914Y0113001*
X0682891Y0112954*
X0682887Y0112949*
Y011294*
X0682876Y0112888*
X068286Y0112839*
X0682836Y0112792*
X0682833Y0112787*
Y0112785*
Y0112778*
X0682822Y0112726*
X0682806Y0112677*
X0682782Y0112629*
X0682762Y0112599*
X0682752Y0112568*
X0682728Y0112521*
X0682708Y0112491*
X06827Y0112467*
X0682697Y011246*
X0682674Y0112413*
X0682654Y0112382*
X0682643Y0112352*
X068262Y0112305*
X06826Y0112274*
X0682592Y0112251*
X0682589Y0112244*
X0682566Y0112197*
X0682546Y0112166*
X0682535Y0112136*
X0682512Y0112089*
X0682483Y0112045*
X0682448Y0112006*
X0682434Y0111993*
X0682427Y0111974*
X0682404Y0111927*
X0682375Y0111883*
X068234Y0111844*
X0682311Y0111818*
X0682286Y011179*
X0682271Y0111777*
X0682265Y0111758*
X0682242Y011171*
X0682213Y0111667*
X0682178Y0111627*
X0682149Y0111602*
X0682124Y0111573*
X0682095Y0111548*
X068208Y0111531*
X068207Y0111519*
X0682041Y0111494*
X0682016Y0111465*
X0681987Y011144*
X0681962Y0111411*
X0681934Y0111387*
X0681933Y0111386*
X0681908Y0111357*
X0681879Y0111332*
X0681854Y0111303*
X0681829Y0111281*
X0681825Y0111278*
X06818Y0111249*
X0681771Y0111224*
X0681746Y0111195*
X0681706Y011116*
X0681663Y0111131*
X0681615Y0111108*
X0681596Y0111101*
X0681583Y0111087*
X0681555Y0111062*
X0681529Y0111033*
X06815Y0111007*
X0681475Y0110979*
X0681436Y0110944*
X0681392Y0110915*
X0681345Y0110892*
X0681326Y0110885*
X0681313Y0110871*
X0681274Y0110836*
X068123Y0110807*
X0681183Y0110784*
X0681153Y0110773*
X0681122Y0110753*
X0681075Y011073*
X0681045Y0110719*
X0681014Y0110699*
X0680967Y0110676*
X0680936Y0110665*
X0680906Y0110645*
X0680859Y0110622*
X0680828Y0110611*
X0680797Y0110591*
X0680751Y0110567*
X068072Y0110557*
X0680689Y0110537*
X0680642Y0110513*
X0680593Y0110496*
X0680541Y0110486*
X0680532*
X0680527Y0110483*
X068048Y0110459*
X0680431Y0110442*
X0680379Y0110432*
X068037*
X0680365Y0110428*
X0680318Y0110405*
X0680268Y0110388*
X0680217Y0110378*
X0680165Y0110375*
X0680149*
Y0110374*
X0680102Y0110351*
X0680052Y0110334*
X0680001Y0110324*
X0679948Y0110321*
X0679879*
Y011032*
X0679832Y0110297*
X0679782Y011028*
X067973Y011027*
X0679678Y0110267*
X0674434*
X0674382Y011027*
X067433Y011028*
X0674281Y0110297*
X0674234Y011032*
X0674233Y0110321*
X0674164*
X0674111Y0110324*
X067406Y0110334*
X067401Y0110351*
X0673963Y0110374*
X0673959Y0110378*
X0673949*
X0673898Y0110388*
X0673848Y0110405*
X0673801Y0110428*
X0673796Y0110432*
X0673787*
X0673736Y0110442*
X0673686Y0110459*
X0673639Y0110483*
X0673634Y0110486*
X0673625*
X0673573Y0110496*
X0673524Y0110513*
X0673477Y0110537*
X0673446Y0110557*
X0673416Y0110567*
X0673369Y0110591*
X0673364Y0110594*
X0673354*
X0673303Y0110605*
X0673253Y0110622*
X0673206Y0110645*
X0673163Y0110674*
X0673123Y0110708*
X067311Y0110723*
X0673091Y011073*
X0673044Y0110753*
X0673013Y0110773*
X0672983Y0110784*
X0672936Y0110807*
X0672893Y0110836*
X0672853Y0110871*
X067284Y0110885*
X0672821Y0110892*
X0672774Y0110915*
X067273Y0110944*
X0672691Y0110979*
X0672678Y0110993*
X0672659Y0111*
X0672612Y0111023*
X0672568Y0111052*
X0672529Y0111087*
X0672516Y0111101*
X0672504Y0111116*
X0672475Y0111141*
X0672449Y011117*
X0672421Y0111195*
X0672395Y0111224*
X0672367Y0111249*
X0672341Y0111278*
X0672337Y0111281*
X0672312Y0111303*
X0672287Y0111332*
X0672258Y0111357*
X0672233Y0111386*
X0672232Y0111387*
X0672204Y0111411*
X0672179Y011144*
X067215Y0111465*
X0672125Y0111494*
X0672096Y0111519*
X0672086Y0111531*
X0672071Y0111548*
X0672042Y0111573*
X0672036Y011158*
X0672017Y0111602*
X0671988Y0111627*
X0671963Y0111656*
X0671934Y0111681*
X06719Y0111721*
X067187Y0111765*
X0671847Y0111811*
X0671844Y0111822*
X0671841Y0111831*
X0671826Y0111844*
X0671801Y0111872*
X0671772Y0111898*
X0671737Y0111937*
X0671708Y0111981*
X0671685Y0112028*
X0671675Y0112058*
X0671654Y0112089*
X0671631Y0112136*
X0671624Y0112155*
X067161Y0112168*
X0671575Y0112207*
X0671546Y0112251*
X0671523Y0112298*
X067152Y0112305*
X0671513Y0112328*
X0671492Y0112359*
X0671469Y0112406*
X0671458Y0112436*
X0671438Y0112467*
X0671415Y0112514*
X0671404Y0112545*
X0671384Y0112575*
X0671361Y0112622*
X0671344Y0112672*
X0671334Y0112724*
X0671333Y0112733*
X067133Y0112738*
X0671307Y0112785*
X067129Y0112834*
X0671279Y0112886*
Y0112895*
X0671276Y01129*
X0671252Y0112947*
X0671236Y0112996*
X0671225Y0113048*
Y0113057*
X0671222Y0113062*
X0671198Y0113109*
X0671181Y0113159*
X0671171Y011321*
X0671168Y0113262*
Y0113317*
Y0113332*
X0671144Y0113379*
X0671128Y0113429*
X0671117Y011348*
X0671114Y0113533*
Y0113587*
Y0113602*
X0671113Y0113603*
X067109Y011365*
X0671073Y0113699*
X0671063Y0113751*
X067106Y0113803*
Y0113857*
Y0113911*
Y0113965*
Y0114019*
Y0114073*
Y0114127*
Y0114181*
Y0114235*
Y011429*
Y0114344*
Y0114398*
Y0114452*
Y0114506*
X0671063Y0114558*
X0671073Y011461*
X067109Y0114659*
X0671113Y0114706*
X0671114Y0114707*
Y0114722*
Y0114776*
Y011483*
Y0114884*
X0671117Y0114937*
X0671128Y0114988*
X0671144Y0115038*
X0671168Y0115085*
Y0115101*
X0671171Y0115153*
X0671181Y0115204*
X0671198Y0115254*
X0671222Y0115301*
Y0115302*
Y0115317*
X0671225Y0115369*
X0671236Y011542*
X0671252Y011547*
X0671276Y0115517*
X0671296Y0115548*
X0671307Y0115578*
X067133Y0115625*
X0671333Y011563*
X0671334Y0115639*
X0671344Y0115691*
X0671361Y0115741*
X0671384Y0115787*
X0671404Y0115818*
X0671406Y0115822*
X0671415Y0115849*
X0671438Y0115896*
X0671458Y0115926*
X0671469Y0115957*
X0671492Y0116004*
X0671513Y0116035*
X0671523Y0116065*
X0671546Y0116112*
X0671562Y0116137*
X0671567Y0116143*
X0671577Y0116173*
X06716Y011622*
X0671629Y0116264*
X0671664Y0116303*
X0671678Y0116316*
X0671685Y0116335*
X0671708Y0116382*
X0671737Y0116426*
X0671772Y0116465*
X0671786Y0116478*
X0671793Y0116497*
X0671816Y0116544*
X0671845Y0116588*
X067188Y0116627*
X0671909Y0116653*
X0671934Y0116682*
X0671963Y0116707*
X0671988Y0116735*
X0672017Y0116761*
X0672042Y011679*
X0672071Y0116815*
X0672096Y0116844*
X0672125Y0116869*
X067215Y0116898*
X0672179Y0116923*
X0672204Y0116952*
X0672233Y0116977*
X0672258Y0117006*
X0672287Y0117031*
X0672312Y011706*
X0672341Y0117085*
X0672367Y0117114*
X0672377Y0117124*
X0672395Y0117139*
X0672421Y0117168*
X0672424Y0117171*
X0672449Y0117193*
X0672475Y0117222*
X0672504Y0117247*
X0672529Y0117276*
X0672557Y0117301*
X0672583Y011733*
X0672622Y0117365*
X0672666Y0117394*
X0672713Y0117417*
X0672732Y0117424*
X0672745Y0117438*
X0672784Y0117473*
X0672828Y0117502*
X0672875Y0117525*
X0672894Y0117532*
X0672907Y0117546*
X0672947Y0117581*
X067299Y011761*
X0673037Y0117633*
X0673068Y0117644*
X0673098Y0117664*
X0673145Y0117687*
X0673176Y0117698*
X0673206Y0117718*
X0673253Y0117742*
X0673284Y0117752*
X0673315Y0117772*
X0673362Y0117796*
X0673411Y0117812*
X0673463Y0117823*
X0673472*
X0673477Y0117826*
X0673524Y011785*
X0673554Y011786*
X0673585Y011788*
X0673632Y0117904*
X0673681Y011792*
X0673733Y0117931*
X0673742*
X0673747Y0117935*
X0673794Y0117958*
X0673844Y0117975*
X0673895Y0117985*
X0673947Y0117988*
X0673963*
Y0117989*
X067401Y0118012*
X067406Y0118029*
X0674111Y0118039*
X0674164Y0118042*
X0674179*
X067418Y0118043*
X0674227Y0118066*
X0674276Y0118083*
X0674328Y0118093*
X067438Y0118096*
X0674774*
Y0118097*
X0674821Y011812*
X0674871Y0118137*
X0674922Y0118147*
X0674975Y011815*
X0679083*
X067911Y0118149*
X0679137Y011815*
X0679191*
X0679244Y0118147*
G37*
G36*
X059734Y0095549D02*
X0597391Y0095539D01*
X0597441Y0095522*
X0597488Y0095499*
X0597504*
X0597556Y0095495*
X0597608Y0095485*
X0597657Y0095468*
X0597704Y0095445*
X0597709Y0095442*
X0597718Y0095441*
X059777Y0095431*
X0597819Y0095414*
X0597866Y0095391*
X0597897Y009537*
X0597928Y009536*
X0597974Y0095337*
X0598005Y0095316*
X0598036Y0095306*
X0598083Y0095283*
X0598126Y0095253*
X0598166Y0095219*
X0598179Y0095204*
X0598198Y0095198*
X0598245Y0095174*
X0598288Y0095145*
X0598328Y0095111*
X0598341Y0095096*
X059836Y009509*
X0598407Y0095066*
X0598451Y0095037*
X059849Y0095003*
X0598515Y0094974*
X0598544Y0094949*
X0598569Y009492*
X0598598Y0094894*
X0598623Y0094866*
X0598652Y009484*
X0598677Y0094812*
X0598706Y0094786*
X0598732Y0094758*
X059876Y0094732*
X0598795Y0094693*
X0598824Y0094649*
X0598847Y0094602*
X0598854Y0094583*
X0598869Y009457*
X0598903Y0094531*
X0598932Y0094487*
X0598955Y009444*
X0598962Y0094421*
X0598977Y0094408*
X0599011Y0094368*
X059904Y0094325*
X0599063Y0094278*
X0599074Y0094248*
X0599094Y0094217*
X0599118Y009417*
X0599134Y009412*
X0599145Y0094069*
Y0094059*
X0599148Y0094055*
X0599172Y0094008*
X0599189Y0093958*
X0599199Y0093906*
Y0093897*
X0599202Y0093892*
X0599226Y0093845*
X0599243Y0093796*
X0599253Y0093744*
X0599256Y0093692*
Y0093677*
X0599257Y0093676*
X059928Y0093629*
X0599297Y009358*
X0599307Y0093528*
X059931Y0093476*
Y0093422*
Y0093368*
Y0093313*
Y009326*
Y0093205*
Y0093151*
Y0093097*
Y0093043*
Y0092989*
Y0092935*
Y0092881*
Y0092827*
Y0092773*
X0599307Y0092721*
X0599297Y0092669*
X059928Y009262*
X0599257Y0092572*
X0599256*
Y0092557*
X0599253Y0092504*
X0599243Y0092453*
X0599226Y0092403*
X0599202Y0092356*
X0599199Y0092352*
Y0092349*
Y0092342*
X0599189Y0092291*
X0599172Y0092241*
X0599148Y0092194*
X0599128Y0092163*
X0599118Y0092133*
X0599094Y0092086*
X0599074Y0092055*
X0599063Y0092025*
X059904Y0091978*
X059902Y0091947*
X059901Y0091917*
X0598986Y009187*
X0598957Y0091826*
X0598922Y0091787*
X0598908Y0091774*
X0598901Y0091755*
X0598878Y0091707*
X0598849Y0091664*
X0598814Y0091624*
X0598786Y0091599*
X059876Y009157*
X0598732Y0091545*
X0598706Y0091516*
X0598677Y0091491*
X0598652Y0091462*
X0598623Y0091437*
X0598598Y0091408*
X0598569Y0091383*
X0598544Y0091354*
X0598515Y0091329*
X059849Y00913*
X0598461Y0091275*
X059844Y009125*
X0598436Y0091246*
X0598407Y0091221*
X0598382Y0091192*
X0598343Y0091157*
X0598299Y0091128*
X0598252Y0091105*
X0598233Y0091098*
X059822Y0091084*
X059818Y0091049*
X0598137Y009102*
X059809Y0090997*
X0598059Y0090987*
X0598029Y0090966*
X0597982Y0090943*
X0597951Y0090933*
X0597921Y0090912*
X0597873Y0090889*
X0597824Y0090872*
X0597772Y0090862*
X0597763Y0090861*
X0597758Y0090858*
X0597711Y0090835*
X0597662Y0090818*
X059761Y0090808*
X0597601Y0090807*
X0597596Y0090804*
X0597549Y0090781*
X0597499Y0090764*
X0597448Y0090754*
X0597396Y009075*
X0597272*
X0597225Y0090727*
X0597175Y009071*
X0597124Y00907*
X0597071Y0090696*
X0596693*
X059664Y00907*
X0596589Y009071*
X0596539Y0090727*
X0596492Y009075*
X0596369*
X0596316Y0090754*
X0596265Y0090764*
X0596215Y0090781*
X0596168Y0090804*
X0596163Y0090807*
X0596154Y0090808*
X0596103Y0090818*
X0596053Y0090835*
X0596006Y0090858*
X0595975Y0090878*
X0595945Y0090889*
X0595898Y0090912*
X0595893Y0090915*
X0595884Y0090916*
X0595832Y0090926*
X0595783Y0090943*
X0595736Y0090966*
X0595692Y0090995*
X0595652Y009103*
X059564Y0091044*
X059562Y0091051*
X0595573Y0091074*
X059553Y0091103*
X059549Y0091138*
X0595477Y0091153*
X0595458Y0091159*
X0595411Y0091182*
X0595368Y0091211*
X0595328Y0091246*
X0595303Y0091275*
X0595274Y00913*
X0595249Y0091329*
X059522Y0091354*
X0595195Y0091383*
X0595166Y0091408*
X0595141Y0091437*
X0595112Y0091462*
X0595087Y0091491*
X0595058Y0091516*
X0595033Y0091545*
X0595004Y009157*
X0594979Y0091599*
X059497Y0091606*
X059495Y0091624*
X0594915Y0091664*
X0594886Y0091707*
X0594863Y0091755*
X0594853Y0091785*
X0594832Y0091816*
X0594809Y0091863*
X0594804Y0091877*
X0594802Y0091882*
X0594788Y0091895*
X0594753Y0091934*
X0594724Y0091978*
X0594701Y0092025*
X059469Y0092055*
X059467Y0092086*
X0594647Y0092133*
X059463Y0092183*
X059462Y0092234*
X0594619Y0092243*
X0594616Y0092248*
X0594593Y0092295*
X0594576Y0092345*
X0594565Y0092396*
Y0092406*
X0594562Y009241*
X0594538Y0092457*
X0594522Y0092507*
X0594511Y0092558*
X0594508Y0092611*
Y0092665*
Y009268*
Y0092681*
X0594484Y0092728*
X0594468Y0092777*
X0594457Y0092829*
X0594454Y0092881*
Y0092935*
Y0092989*
Y0093043*
Y0093097*
Y0093151*
Y0093205*
Y009326*
Y0093313*
Y0093368*
Y0093422*
X0594457Y0093474*
X0594468Y0093525*
X0594484Y0093575*
X0594508Y0093622*
Y0093623*
Y0093638*
Y0093692*
X0594511Y0093744*
X0594522Y0093796*
X0594538Y0093845*
X0594562Y0093892*
X0594565Y0093897*
Y0093906*
X0594576Y0093958*
X0594593Y0094008*
X0594616Y0094055*
X0594636Y0094085*
X0594647Y0094116*
X059467Y0094163*
X059469Y0094194*
X0594701Y0094224*
X0594724Y0094271*
X0594744Y0094302*
X0594755Y0094332*
X0594778Y0094379*
X0594799Y009441*
X0594809Y009444*
X0594832Y0094487*
X0594861Y0094531*
X0594896Y009457*
X0594924Y0094595*
X059495Y0094624*
X0594964Y0094637*
X0594971Y0094656*
X0594994Y0094703*
X0595023Y0094747*
X0595058Y0094786*
X0595087Y0094812*
X0595112Y009484*
X0595141Y0094866*
X0595166Y0094894*
X0595195Y009492*
X059522Y0094949*
X059526Y0094983*
X0595303Y0095012*
X059535Y0095035*
X0595369Y0095042*
X0595382Y0095057*
X0595411Y0095082*
X0595436Y0095111*
X0595476Y0095145*
X0595519Y0095174*
X0595566Y0095198*
X0595586Y0095204*
X0595599Y0095219*
X0595638Y0095253*
X0595681Y0095283*
X0595728Y0095306*
X0595759Y0095316*
X059579Y0095337*
X0595837Y009536*
X0595886Y0095377*
X0595938Y0095387*
X0595947Y0095388*
X0595952Y0095391*
X0595999Y0095414*
X0596004Y0095416*
X0596029Y0095424*
X059606Y0095445*
X0596107Y0095468*
X0596157Y0095485*
X0596208Y0095495*
X059626Y0095499*
X0596276*
X0596323Y0095522*
X0596373Y0095539*
X0596424Y0095549*
X0596477Y0095552*
X0597288*
X059734Y0095549*
G37*
G36*
X0597286Y0088251D02*
X0597337Y008824D01*
X0597387Y0088224*
X0597434Y00882*
X0597435*
X059745*
X0597502Y0088197*
X0597553Y0088186*
X0597603Y008817*
X059765Y0088146*
X0597655Y0088143*
X0597664*
X0597716Y0088132*
X0597765Y0088116*
X0597812Y0088092*
X0597843Y0088072*
X0597873Y0088061*
X0597921Y0088038*
X0597951Y0088018*
X0597982Y0088007*
X0598029Y0087984*
X0598059Y0087964*
X059809Y0087953*
X0598137Y008793*
X0598168Y008791*
X0598198Y0087899*
X0598245Y0087876*
X0598288Y0087847*
X0598328Y0087812*
X0598353Y0087784*
X0598382Y0087758*
X0598395Y0087744*
X0598414Y0087737*
X0598461Y0087714*
X0598505Y0087685*
X0598544Y008765*
X0598569Y0087621*
X0598598Y0087596*
X0598624Y0087567*
X0598652Y0087542*
X0598677Y0087513*
X0598706Y0087488*
X0598741Y0087449*
X059877Y0087405*
X0598793Y0087358*
X05988Y0087339*
X0598814Y0087326*
X059884Y0087297*
X0598869Y0087272*
X0598903Y0087232*
X0598932Y0087189*
X0598955Y0087142*
X0598966Y0087111*
X0598986Y0087081*
X059901Y0087034*
X059902Y0087003*
X059904Y0086972*
X0599063Y0086925*
X0599074Y0086895*
X0599094Y0086864*
X0599118Y0086817*
X0599128Y0086787*
X0599148Y0086756*
X0599172Y0086709*
X0599189Y0086659*
X0599199Y0086608*
Y0086599*
X0599202Y0086594*
X0599226Y0086547*
X0599243Y0086497*
X0599253Y0086446*
X0599256Y0086394*
Y0086378*
X0599257*
X059928Y0086331*
X0599297Y0086281*
X0599307Y008623*
X059931Y0086177*
Y0086123*
Y0086069*
Y0086015*
Y0085961*
Y0085907*
Y0085853*
Y0085799*
Y0085745*
Y0085691*
Y0085637*
Y0085583*
Y0085529*
Y0085474*
X0599307Y0085422*
X0599297Y0085371*
X059928Y0085321*
X0599257Y0085274*
X0599256*
Y0085258*
X0599253Y0085206*
X0599243Y0085154*
X0599226Y0085105*
X0599202Y0085058*
X0599199Y0085053*
Y0085044*
X0599189Y0084992*
X0599172Y0084943*
X0599148Y0084896*
X0599128Y0084865*
X0599118Y0084835*
X0599094Y0084788*
X0599074Y0084757*
X0599071Y0084749*
X0599063Y0084727*
X059904Y0084679*
X059902Y0084649*
X059901Y0084618*
X0598986Y0084571*
X0598966Y008454*
X0598955Y008451*
X0598932Y0084463*
X0598903Y008442*
X0598869Y008438*
X059884Y0084355*
X0598814Y0084326*
X05988Y0084313*
X0598793Y0084294*
X059877Y0084247*
X0598741Y0084203*
X0598706Y0084164*
X0598677Y0084139*
X0598652Y008411*
X0598623Y0084085*
X0598598Y0084056*
X0598559Y0084021*
X0598515Y0083992*
X0598468Y0083969*
X0598449Y0083962*
X0598436Y0083948*
X0598407Y0083922*
X0598382Y0083894*
X0598353Y0083868*
X0598328Y0083839*
X0598288Y0083805*
X0598245Y0083776*
X0598198Y0083753*
X0598168Y0083742*
X0598137Y0083722*
X059809Y0083699*
X0598059Y0083688*
X0598029Y0083668*
X0597982Y0083644*
X0597951Y0083634*
X0597921Y0083614*
X0597873Y0083591*
X0597843Y008358*
X0597812Y008356*
X0597765Y0083536*
X0597716Y008352*
X0597664Y0083509*
X0597655*
X059765Y0083505*
X0597603Y0083482*
X0597553Y0083465*
X0597502Y0083455*
X059745Y0083452*
X059738*
Y0083451*
X0597333Y0083428*
X0597283Y0083411*
X0597232Y0083401*
X0597179Y0083398*
X0596585*
X0596532Y0083401*
X0596481Y0083411*
X0596431Y0083428*
X0596384Y0083451*
Y0083452*
X0596314*
X0596262Y0083455*
X0596211Y0083465*
X0596161Y0083482*
X0596114Y0083505*
X0596109Y0083509*
X05961*
X0596048Y008352*
X0595999Y0083536*
X0595952Y008356*
X0595921Y008358*
X0595891Y0083591*
X0595844Y0083614*
X0595813Y0083634*
X0595783Y0083644*
X0595736Y0083668*
X0595705Y0083688*
X0595675Y0083699*
X0595627Y0083722*
X0595584Y0083751*
X0595544Y0083785*
X0595532Y00838*
X0595512Y0083807*
X0595465Y008383*
X0595422Y0083859*
X0595382Y0083894*
X0595357Y0083922*
X0595328Y0083948*
X0595303Y0083977*
X0595274Y0084002*
X0595249Y0084031*
X059522Y0084056*
X0595195Y0084085*
X0595166Y008411*
X0595141Y0084139*
X0595112Y0084164*
X0595087Y0084193*
X0595058Y0084218*
X0595033Y0084247*
X0595004Y0084272*
X0594979Y0084301*
X059495Y0084326*
X0594915Y0084365*
X0594886Y0084409*
X0594863Y0084456*
X0594856Y0084475*
X0594842Y0084488*
X0594807Y0084528*
X0594778Y0084571*
X0594755Y0084618*
X0594744Y0084649*
X0594724Y0084679*
X0594701Y0084727*
X0594696Y0084741*
X059469Y0084757*
X059467Y0084788*
X0594647Y0084835*
X059463Y0084884*
X059462Y0084936*
X0594619Y0084945*
X0594616Y008495*
X0594593Y0084997*
X0594576Y0085046*
X0594565Y0085098*
Y0085107*
X0594562Y0085112*
X0594538Y0085159*
X0594522Y0085209*
X0594511Y008526*
X0594508Y0085312*
Y0085328*
X0594484Y0085375*
X0594468Y0085425*
X0594457Y0085476*
X0594454Y0085529*
Y0085583*
Y0085637*
Y0085691*
Y0085745*
Y0085799*
Y0085853*
Y0085907*
Y0085961*
Y0086015*
Y0086069*
Y0086123*
X0594457Y0086176*
X0594468Y0086227*
X0594484Y0086277*
X0594508Y0086324*
Y0086339*
X0594511Y0086392*
X0594522Y0086443*
X0594538Y0086493*
X0594562Y008654*
Y0086541*
Y0086556*
X0594565Y0086608*
X0594576Y0086659*
X0594593Y0086709*
X0594616Y0086756*
X0594626Y0086772*
X0594636Y0086787*
X0594647Y0086817*
X059467Y0086864*
X059469Y0086895*
X0594701Y0086925*
X0594724Y0086972*
X0594744Y0087003*
X0594755Y0087034*
X0594778Y0087081*
X0594807Y0087124*
X0594842Y0087164*
X0594856Y0087177*
X0594863Y0087196*
X0594886Y0087243*
X0594915Y0087286*
X059495Y0087326*
X0594964Y0087339*
X0594979Y0087351*
X0595004Y008738*
X0595015Y0087389*
X0595033Y0087405*
X0595058Y0087434*
X0595087Y0087459*
X0595112Y0087488*
X0595141Y0087513*
X0595166Y0087542*
X0595195Y0087567*
X059522Y0087596*
X0595249Y0087621*
X0595274Y008765*
X0595303Y0087675*
X0595328Y0087704*
X0595357Y008773*
X0595382Y0087758*
X0595422Y0087793*
X0595465Y0087822*
X0595512Y0087845*
X0595532Y0087852*
X0595544Y0087866*
X0595584Y0087901*
X0595627Y008793*
X0595675Y0087953*
X0595705Y0087964*
X0595736Y0087984*
X0595783Y0088007*
X0595813Y0088018*
X0595844Y0088038*
X0595891Y0088061*
X0595921Y0088072*
X0595952Y0088092*
X0595999Y0088116*
X0596048Y0088132*
X05961Y0088143*
X0596109*
X0596114Y0088146*
X0596161Y008817*
X0596211Y0088186*
X0596262Y0088197*
X0596314Y00882*
X0596384*
X0596431Y0088224*
X0596481Y008824*
X0596532Y0088251*
X0596585Y0088254*
X0597233*
X0597286Y0088251*
G37*
G36*
X0691678Y0089927D02*
X0691729Y0089916D01*
X0691779Y0089899*
X0691826Y0089876*
X0691827*
X069195*
X0692002Y0089873*
X0692054Y0089862*
X0692103Y0089846*
X0692151Y0089822*
X0692166*
X0692219Y0089819*
X069227Y0089808*
X069232Y0089791*
X0692367Y0089768*
X0692372Y0089765*
X0692381Y0089764*
X0692432Y0089754*
X0692482Y0089737*
X0692529Y0089714*
X0692534Y0089711*
X0692543Y008971*
X0692594Y00897*
X0692644Y0089683*
X0692691Y008966*
X0692722Y008964*
X0692752Y0089629*
X0692799Y0089606*
X0692804Y0089603*
X0692813Y0089602*
X0692865Y0089592*
X0692914Y0089575*
X0692962Y0089552*
X0692992Y0089531*
X0693023Y0089521*
X069307Y0089498*
X0693113Y0089469*
X0693153Y0089434*
X0693165Y008942*
X0693185Y0089413*
X0693232Y008939*
X0693263Y0089369*
X0693293Y0089359*
X069334Y0089336*
X0693384Y0089307*
X0693423Y0089272*
X0693436Y0089257*
X0693455Y0089251*
X0693502Y0089228*
X0693546Y0089198*
X0693585Y0089164*
X069361Y0089135*
X0693639Y008911*
X0693665Y0089081*
X0693693Y0089056*
X0693706Y0089041*
X0693725Y0089035*
X0693772Y0089011*
X0693816Y0088982*
X0693855Y0088948*
X0693881Y0088919*
X069391Y0088894*
X0693935Y0088865*
X0693964Y008884*
X0693989Y0088811*
X0694018Y0088785*
X0694043Y0088757*
X0694072Y0088731*
X0694097Y0088703*
X0694126Y0088677*
X0694151Y0088649*
X069418Y0088623*
X0694205Y0088594*
X0694234Y0088569*
X0694268Y008853*
X0694298Y0088486*
X0694321Y0088439*
X0694327Y008842*
X0694342Y0088407*
X0694367Y0088378*
X0694396Y0088353*
X0694431Y0088314*
X069446Y008827*
X0694483Y0088223*
X0694489Y0088204*
X0694504Y0088191*
X0694539Y0088151*
X0694568Y0088108*
X0694591Y0088061*
X0694601Y008803*
X0694622Y0088*
X0694645Y0087953*
X0694652Y0087933*
X0694666Y008792*
X0694701Y0087881*
X069473Y0087837*
X0694753Y008779*
X0694764Y008776*
X0694784Y0087729*
X0694807Y0087682*
X0694824Y0087633*
X0694834Y0087581*
X0694835Y0087572*
X0694838Y0087567*
X0694861Y008752*
X0694872Y008749*
X0694888Y0087466*
X0694892Y0087459*
X0694915Y0087412*
X0694932Y0087362*
X0694943Y0087311*
Y0087302*
X0694946Y0087297*
X069497Y008725*
X0694986Y00872*
X0694997Y0087149*
Y0087139*
X0695Y0087135*
X0695024Y0087088*
X069504Y0087038*
X0695051Y0086987*
X0695054Y0086934*
Y0086919*
Y0086918*
X0695078Y0086871*
X0695094Y0086822*
X0695105Y008677*
X0695108Y0086718*
Y0086664*
Y008661*
Y0086595*
X0695109Y0086594*
X0695132Y0086547*
X0695149Y0086497*
X0695159Y0086446*
X0695162Y0086394*
Y0086339*
Y0086286*
Y0086231*
Y0086177*
Y0086123*
Y0086069*
Y0086015*
Y0085961*
Y0085907*
Y0085853*
Y0085799*
Y0085745*
Y0085691*
Y0085637*
Y0085583*
X0695159Y008553*
X0695149Y0085479*
X0695132Y0085429*
X0695109Y0085382*
X0695108*
Y0085366*
Y0085312*
Y0085258*
X0695105Y0085206*
X0695094Y0085154*
X0695078Y0085105*
X0695054Y0085058*
Y0085057*
Y0085042*
X0695051Y008499*
X069504Y0084938*
X0695024Y0084889*
X0695Y0084842*
X0694997Y0084837*
Y0084828*
X0694986Y0084776*
X069497Y0084727*
X0694946Y0084679*
X0694943Y0084675*
Y0084665*
X0694932Y0084614*
X0694915Y0084564*
X0694892Y0084517*
X0694872Y0084486*
X0694861Y0084456*
X0694838Y0084409*
X0694818Y0084378*
X0694807Y0084348*
X0694784Y0084301*
X0694764Y008427*
X0694753Y008424*
X069473Y0084193*
X0694709Y0084162*
X0694699Y0084132*
X0694676Y0084085*
X0694655Y0084054*
X0694645Y0084024*
X0694622Y0083977*
X0694593Y0083933*
X0694558Y0083894*
X0694544Y0083881*
X0694537Y0083862*
X0694514Y0083814*
X0694485Y0083771*
X069445Y0083731*
X0694435Y0083719*
X0694429Y0083699*
X0694406Y0083652*
X0694377Y0083609*
X0694342Y0083569*
X0694313Y0083544*
X0694288Y0083515*
X0694263Y0083493*
X0694259Y008349*
X0694234Y0083461*
X0694205Y0083436*
X069419Y0083419*
X069418Y0083407*
X0694151Y0083382*
X0694126Y0083353*
X0694097Y0083328*
X0694072Y0083299*
X0694043Y0083274*
X0694018Y0083245*
X0693989Y008322*
X0693964Y0083191*
X0693935Y0083166*
X069391Y0083137*
X0693881Y0083112*
X0693855Y0083083*
X0693831Y0083061*
X0693827Y0083057*
X0693801Y0083029*
X0693773Y0083003*
X0693747Y0082975*
X0693722Y0082953*
X0693718Y0082949*
X0693693Y008292*
X0693654Y0082886*
X069361Y0082857*
X0693563Y0082834*
X0693544Y0082827*
X0693531Y0082812*
X0693502Y0082787*
X0693477Y0082758*
X0693438Y0082724*
X0693394Y0082695*
X0693347Y0082671*
X0693317Y0082661*
X0693286Y008264*
X0693239Y0082617*
X069322Y0082611*
X0693207Y0082596*
X0693167Y0082561*
X0693124Y0082532*
X0693077Y0082509*
X0693046Y0082499*
X0693015Y0082478*
X0692969Y0082455*
X0692938Y0082445*
X0692907Y0082424*
X069286Y0082401*
X0692811Y0082384*
X0692759Y0082374*
X069275Y0082373*
X0692745Y008237*
X0692698Y0082347*
X0692668Y0082337*
X0692637Y0082316*
X069259Y0082293*
X069254Y0082276*
X0692489Y0082266*
X069248Y0082265*
X0692475Y0082262*
X0692428Y0082239*
X0692378Y0082222*
X0692327Y0082212*
X0692275Y0082208*
X0692259*
X0692212Y0082185*
X0692162Y0082168*
X0692111Y0082158*
X0692058Y0082154*
X0691989*
X0691988*
X0691941Y0082131*
X0691892Y0082114*
X069184Y0082104*
X0691788Y00821*
X0691665*
X0691664*
X0691617Y0082077*
X0691567Y008206*
X0691516Y008205*
X0691464Y0082046*
X0691409*
X0691383Y0082048*
X0691356Y0082046*
X0691301*
X0691274Y0082048*
X0691247Y0082046*
X0690869*
X0690817Y008205*
X0690765Y008206*
X0690716Y0082077*
X0690668Y00821*
X069049*
X0690438Y0082104*
X0690387Y0082114*
X0690337Y0082131*
X069029Y0082154*
X0690289*
X069022*
X0690168Y0082158*
X0690116Y0082168*
X0690067Y0082185*
X069002Y0082208*
X0690015Y0082211*
X0690006Y0082212*
X0689954Y0082222*
X0689905Y0082239*
X0689857Y0082262*
X0689853Y0082265*
X0689844Y0082266*
X0689792Y0082276*
X0689742Y0082293*
X0689695Y0082316*
X0689691Y0082319*
X0689681Y008232*
X068963Y008233*
X068958Y0082347*
X0689533Y008237*
X0689502Y0082391*
X0689472Y0082401*
X0689425Y0082424*
X0689394Y0082445*
X0689364Y0082455*
X0689317Y0082478*
X0689286Y0082499*
X0689256Y0082509*
X0689209Y0082532*
X0689178Y0082553*
X0689148Y0082563*
X0689101Y0082586*
X0689057Y0082616*
X0689018Y008265*
X0689005Y0082665*
X0688985Y0082671*
X0688939Y0082695*
X0688895Y0082724*
X0688856Y0082758*
X0688843Y0082773*
X0688823Y008278*
X0688776Y0082803*
X0688733Y0082832*
X0688693Y0082866*
X0688668Y0082895*
X0688639Y008292*
X0688614Y0082949*
X068861Y0082953*
X0688585Y0082975*
X0688572Y0082989*
X0688553Y0082996*
X0688506Y0083019*
X0688462Y0083048*
X0688423Y0083083*
X0688398Y0083112*
X0688369Y0083137*
X0688344Y0083166*
X0688315Y0083191*
X068829Y008322*
X0688261Y0083245*
X0688251Y0083256*
X0688236Y0083274*
X0688207Y0083299*
X0688181Y0083328*
X0688153Y0083353*
X0688118Y0083392*
X0688089Y0083436*
X0688066Y0083483*
X0688059Y0083502*
X0688045Y0083515*
X0688034Y0083527*
X0688019Y0083544*
X0687991Y0083569*
X068798Y0083581*
X0687965Y0083598*
X0687936Y0083623*
X0687902Y0083663*
X0687873Y0083706*
X068785Y0083753*
X0687843Y0083773*
X0687828Y0083785*
X0687794Y0083825*
X0687765Y0083868*
X0687741Y0083916*
X0687731Y0083946*
X0687711Y0083977*
X0687687Y0084024*
X0687686Y0084028*
X0687681Y0084043*
X0687666Y0084056*
X0687632Y0084095*
X0687602Y0084139*
X0687579Y0084186*
X0687577Y0084193*
X0687569Y0084216*
X0687548Y0084247*
X0687525Y0084294*
X0687515Y0084324*
X0687494Y0084355*
X0687471Y0084402*
X0687454Y0084452*
X0687444Y0084503*
X0687443Y0084513*
X068744Y0084517*
X0687417Y0084564*
X0687407Y0084595*
X0687386Y0084625*
X0687363Y0084672*
X0687346Y0084722*
X0687336Y0084773*
X0687335Y0084783*
X0687332Y0084788*
X0687309Y0084835*
X0687292Y0084884*
X0687282Y0084936*
X0687278Y0084988*
Y0085003*
Y0085004*
X0687255Y0085051*
X0687238Y0085101*
X0687228Y0085152*
X0687224Y0085204*
Y0085258*
Y0085274*
X0687201Y0085321*
X0687184Y0085371*
X0687174Y0085422*
X068717Y0085474*
Y0085529*
Y0085583*
Y0085637*
Y0085691*
Y0085745*
Y0085799*
Y0085853*
Y0085907*
Y0085961*
Y0086015*
Y0086069*
Y0086123*
Y0086177*
Y0086231*
Y0086286*
Y0086339*
Y0086394*
Y0086448*
Y0086502*
X0687174Y0086554*
X0687184Y0086606*
X0687201Y0086655*
X0687224Y0086702*
Y0086703*
Y0086718*
Y0086772*
X0687228Y0086824*
X0687238Y0086876*
X0687255Y0086925*
X0687278Y0086972*
Y0086973*
Y0086988*
X0687282Y0087041*
X0687292Y0087092*
X0687309Y0087142*
X0687332Y0087189*
X0687335Y0087193*
X0687336Y0087203*
X0687346Y0087254*
X0687363Y0087304*
X0687386Y0087351*
X0687389Y0087356*
X068739Y0087365*
X06874Y0087416*
X0687417Y0087466*
X068744Y0087513*
X0687461Y0087544*
X0687471Y0087574*
X0687494Y0087621*
X0687515Y0087652*
X0687525Y0087682*
X0687548Y0087729*
X0687554Y0087737*
X0687569Y008776*
X0687579Y008779*
X0687602Y0087837*
X0687623Y0087868*
X0687633Y0087899*
X0687656Y0087946*
X0687677Y0087976*
X0687687Y0088007*
X0687711Y0088054*
X068774Y0088097*
X0687774Y0088137*
X0687789Y008815*
X0687795Y0088169*
X0687819Y0088216*
X0687848Y008826*
X0687882Y0088299*
X0687911Y0088324*
X0687936Y0088353*
X0687951Y0088366*
X0687958Y0088385*
X0687981Y0088432*
X068801Y0088476*
X0688045Y0088515*
X0688073Y008854*
X0688099Y0088569*
X0688127Y0088594*
X0688153Y0088623*
X0688181Y0088649*
X0688207Y0088677*
X0688236Y0088703*
X0688261Y0088731*
X068829Y0088757*
X0688315Y0088785*
X0688344Y0088811*
X0688369Y008884*
X0688398Y0088865*
X0688423Y0088894*
X0688452Y0088919*
X0688477Y0088948*
X0688506Y0088973*
X0688531Y0089002*
X068856Y0089027*
X0688585Y0089056*
X0688625Y008909*
X0688668Y0089119*
X0688715Y0089143*
X0688734Y0089149*
X0688747Y0089164*
X0688787Y0089198*
X068883Y0089228*
X0688877Y0089251*
X0688897Y0089257*
X0688909Y0089272*
X0688949Y0089307*
X0688993Y0089336*
X068904Y0089359*
X0689059Y0089366*
X0689072Y008938*
X0689111Y0089415*
X0689155Y0089444*
X0689202Y0089467*
X0689232Y0089477*
X0689263Y0089498*
X068931Y0089521*
X068934Y0089531*
X0689371Y0089552*
X0689418Y0089575*
X0689448Y0089586*
X0689479Y0089606*
X0689526Y0089629*
X0689576Y0089646*
X0689627Y0089656*
X0689637Y0089657*
X0689641Y008966*
X0689688Y0089683*
X0689738Y00897*
X0689789Y008971*
X0689799Y0089711*
X0689804Y0089714*
X0689851Y0089737*
X06899Y0089754*
X0689952Y0089764*
X0689961Y0089765*
X0689966Y0089768*
X0690013Y0089791*
X0690062Y0089808*
X0690114Y0089819*
X0690166Y0089822*
X0690181*
X0690182*
X0690229Y0089846*
X0690279Y0089862*
X069033Y0089873*
X0690382Y0089876*
X0690452*
X0690499Y0089899*
X0690549Y0089916*
X06906Y0089927*
X0690653Y008993*
X0691626*
X0691678Y0089927*
G37*
G36*
X0662971Y0118147D02*
X0663023Y0118137D01*
X0663072Y011812*
X0663119Y0118097*
X066312Y0118096*
X0663514*
X0663566Y0118093*
X0663617Y0118083*
X0663667Y0118066*
X0663714Y0118043*
X0663715Y0118042*
X066373*
X0663782Y0118039*
X0663834Y0118029*
X0663883Y0118012*
X066393Y0117989*
X0663931Y0117988*
X0663946*
X0663998Y0117985*
X066405Y0117975*
X0664099Y0117958*
X0664146Y0117935*
X0664151Y0117931*
X066416*
X0664212Y011792*
X0664262Y0117904*
X0664309Y011788*
X0664313Y0117877*
X0664323*
X0664374Y0117867*
X0664424Y011785*
X0664471Y0117826*
X0664502Y0117806*
X0664532Y0117796*
X0664579Y0117772*
X066461Y0117752*
X066464Y0117742*
X0664687Y0117718*
X0664718Y0117698*
X0664748Y0117687*
X0664795Y0117664*
X0664826Y0117644*
X0664856Y0117633*
X0664903Y011761*
X0664934Y011759*
X0664964Y0117579*
X0665011Y0117556*
X0665055Y0117527*
X0665094Y0117492*
X0665107Y0117478*
X0665127Y0117471*
X0665174Y0117448*
X0665217Y0117419*
X0665257Y0117384*
X0665282Y0117355*
X0665311Y011733*
X0665324Y0117315*
X0665343Y0117309*
X066539Y0117286*
X0665434Y0117257*
X0665473Y0117222*
X0665498Y0117193*
X0665527Y0117168*
X0665552Y0117139*
X0665581Y0117114*
X0665606Y0117085*
X0665635Y011706*
X066566Y0117031*
X0665689Y0117006*
X0665714Y0116977*
X0665743Y0116952*
X0665768Y0116923*
X0665797Y0116898*
X0665823Y0116869*
X0665851Y0116844*
X0665877Y0116815*
X0665905Y011679*
X0665931Y0116761*
X0665959Y0116735*
X0665985Y0116707*
X0666013Y0116682*
X0666048Y0116642*
X0666077Y0116598*
X06661Y0116551*
X0666107Y0116532*
X0666122Y0116519*
X0666147Y011649*
X0666176Y0116465*
X066621Y0116426*
X0666239Y0116382*
X0666263Y0116335*
X0666273Y0116305*
X0666293Y0116274*
X0666317Y0116227*
X0666323Y0116208*
X0666338Y0116195*
X0666372Y0116156*
X0666402Y0116112*
X0666425Y0116065*
X0666435Y0116035*
X0666456Y0116004*
X0666479Y0115957*
X0666489Y0115926*
X0666499Y0115911*
X066651Y0115896*
X0666533Y0115849*
X0666542Y0115822*
X0666543Y0115818*
X0666564Y0115787*
X0666587Y0115741*
X0666604Y0115691*
X0666614Y0115639*
X0666615Y011563*
X0666618Y0115625*
X0666641Y0115578*
X0666658Y0115529*
X0666668Y0115477*
X0666669Y0115468*
X0666672Y0115463*
X0666695Y0115416*
X0666712Y0115366*
X0666722Y0115315*
X0666723Y0115306*
X0666726Y0115301*
X0666749Y0115254*
X0666766Y0115204*
X0666776Y0115153*
X066678Y0115101*
Y0115085*
X0666803Y0115038*
X066682Y0114988*
X066683Y0114937*
X0666834Y0114884*
Y011483*
Y0114776*
Y0114761*
Y011476*
X0666857Y0114713*
X0666874Y0114664*
X0666884Y0114612*
X0666888Y011456*
Y0114506*
Y0114452*
Y0114398*
Y0114344*
Y011429*
Y0114235*
Y0114181*
Y0114127*
Y0114073*
Y0114019*
Y0113965*
X0666886Y0113938*
X0666888Y0113911*
Y0113857*
X0666884Y0113805*
X0666874Y0113753*
X0666857Y0113704*
X0666834Y0113657*
Y0113656*
Y0113641*
Y0113587*
Y0113533*
Y0113479*
X066683Y0113426*
X066682Y0113375*
X0666803Y0113325*
X066678Y0113278*
Y0113262*
X0666776Y011321*
X0666766Y0113159*
X0666749Y0113109*
X0666726Y0113062*
X0666723Y0113057*
X0666722Y0113048*
X0666712Y0112996*
X0666695Y0112947*
X0666672Y01129*
X0666669Y0112895*
X0666668Y0112886*
X0666658Y0112834*
X0666641Y0112785*
X0666618Y0112738*
X0666615Y0112733*
X0666614Y0112724*
X0666604Y0112672*
X0666587Y0112622*
X0666564Y0112575*
X0666543Y0112545*
X0666533Y0112514*
X066651Y0112467*
X0666489Y0112436*
X0666479Y0112406*
X0666456Y0112359*
X0666435Y0112328*
X0666425Y0112298*
X0666402Y0112251*
X0666372Y0112207*
X0666338Y0112168*
X0666323Y0112155*
X0666317Y0112136*
X0666293Y0112089*
X0666264Y0112045*
X066623Y0112006*
X0666215Y0111993*
X0666209Y0111974*
X0666185Y0111927*
X0666156Y0111883*
X0666122Y0111844*
X0666093Y0111818*
X0666068Y011179*
X0666053Y0111777*
X0666046Y0111758*
X0666023Y011171*
X0665994Y0111667*
X0665959Y0111627*
X0665931Y0111602*
X0665905Y0111573*
X0665877Y0111548*
X0665857Y0111526*
X0665851Y0111519*
X0665823Y0111494*
X0665805Y0111474*
X0665797Y0111465*
X0665768Y011144*
X0665743Y0111411*
X0665714Y0111386*
X0665689Y0111357*
X066566Y0111332*
X0665635Y0111303*
X0665608Y0111279*
X0665606Y0111278*
X0665581Y0111249*
X0665556Y0111227*
X0665552Y0111224*
X0665527Y0111195*
X0665487Y011116*
X0665444Y0111131*
X0665397Y0111108*
X0665378Y0111102*
Y0111101*
X0665365Y0111087*
X0665336Y0111062*
X0665311Y0111033*
X0665271Y0110998*
X0665228Y0110969*
X0665181Y0110946*
X0665161Y0110939*
X0665159Y0110936*
X0665148Y0110925*
X0665109Y011089*
X0665065Y0110861*
X0665019Y0110838*
X0664999Y0110831*
X0664986Y0110817*
X0664947Y0110782*
X0664903Y0110753*
X0664856Y011073*
X0664826Y0110719*
X0664795Y0110699*
X0664748Y0110676*
X066472Y0110666*
X0664718Y0110665*
X0664709Y0110659*
X0664687Y0110645*
X066464Y0110622*
X066461Y0110611*
X0664579Y0110591*
X0664532Y0110567*
X0664482Y0110551*
X0664431Y011054*
X0664422*
X0664417Y0110537*
X066437Y0110513*
X0664339Y0110503*
X0664331Y0110497*
X0664309Y0110483*
X0664262Y0110459*
X0664212Y0110442*
X066416Y0110432*
X0664108Y0110429*
X0664093*
X0664092Y0110428*
X0664045Y0110405*
X0663996Y0110388*
X0663944Y0110378*
X0663935*
X066393Y0110374*
X0663883Y0110351*
X0663834Y0110334*
X0663782Y0110324*
X066373Y0110321*
X0663606*
Y011032*
X0663559Y0110297*
X0663509Y011028*
X0663458Y011027*
X0663405Y0110267*
X0655443*
X0655442Y0110266*
X0655395Y0110243*
X0655346Y0110226*
X0655294Y0110216*
X0655242Y0110213*
X0655011*
X065501Y0110212*
X0654963Y0110189*
X0654913Y0110172*
X0654862Y0110162*
X065481Y0110159*
X0654794*
Y0110158*
X0654747Y0110135*
X0654697Y0110118*
X0654646Y0110108*
X0654593Y0110104*
X0654578*
X0654577*
X065453Y0110081*
X06545Y0110071*
X0654491Y0110065*
X0654469Y011005*
X0654422Y0110027*
X0654373Y011001*
X0654321Y011*
X0654312Y0109999*
X0654307Y0109996*
X065426Y0109973*
X065423Y0109962*
X0654199Y0109942*
X0654152Y0109919*
X0654122Y0109908*
X0654091Y0109888*
X0654044Y0109865*
X0654014Y0109854*
X0653983Y0109834*
X0653936Y010981*
X0653917Y0109804*
X0653904Y0109789*
X0653864Y0109755*
X0653821Y0109726*
X0653774Y0109702*
X0653743Y0109692*
X0653713Y0109672*
X0653665Y0109648*
X0653646Y0109642*
X0653639Y0109634*
X0653633Y0109627*
X0653605Y0109602*
X0653587Y0109582*
X0653579Y0109573*
X065355Y0109548*
X0653525Y0109519*
X0653486Y0109484*
X0653442Y0109455*
X0653395Y0109432*
X0653376Y0109426*
X0653363Y0109411*
X0653334Y0109386*
X0653309Y0109357*
X065328Y0109332*
X0653255Y0109303*
X0653226Y0109277*
X0653201Y0109249*
X0653172Y0109223*
X0653164Y0109214*
X0653147Y0109195*
X0653132Y0109182*
X0653125Y0109162*
X0653102Y0109116*
X0653073Y0109072*
X0653039Y0109032*
X065301Y0109007*
X0652996Y0108992*
X0652985Y0108978*
X065297Y0108966*
X0652963Y0108946*
X065294Y0108899*
X0652911Y0108856*
X0652876Y0108816*
X0652862Y0108803*
X0652855Y0108784*
X0652832Y0108737*
X0652803Y0108693*
X0652768Y0108654*
X0652754Y0108641*
X0652751Y0108632*
X0652747Y0108622*
X0652724Y0108575*
X0652703Y0108544*
X0652693Y0108514*
X065267Y0108467*
X0652649Y0108436*
X0652647Y0108428*
X0652639Y0108406*
X0652616Y0108359*
X0652613Y0108354*
X0652612Y0108344*
X0652602Y0108293*
X0652585Y0108243*
X0652562Y0108196*
X0652541Y0108166*
X0652531Y0108135*
X0652508Y0108088*
X0652504Y0108083*
Y0108074*
X0652494Y0108023*
X0652477Y0107973*
X0652454Y0107926*
X0652453*
Y010791*
X065245Y0107858*
X065244Y0107807*
X0652423Y0107757*
X0652399Y010771*
Y0107709*
Y0107694*
Y010764*
Y0107586*
X0652396Y0107534*
X0652386Y0107482*
X0652369Y0107432*
X0652345Y0107386*
Y0107385*
Y010737*
Y0107316*
Y0107262*
Y0107208*
Y0107153*
Y0107099*
Y0107045*
Y0106991*
Y0106937*
Y0106922*
Y0106921*
X0652369Y0106874*
X0652386Y0106825*
X0652396Y0106773*
X0652399Y0106721*
Y0106667*
Y0106613*
Y0106597*
X0652423Y010655*
X065244Y01065*
X065245Y0106449*
X0652453Y0106397*
Y0106381*
X0652454*
X0652477Y0106334*
X0652494Y0106284*
X0652504Y0106233*
Y0106223*
X0652508Y0106219*
X0652531Y0106172*
X0652548Y0106122*
X0652558Y010607*
X0652559Y0106061*
X0652562Y0106056*
X0652585Y0106009*
X0652595Y0105979*
X0652616Y0105948*
X0652639Y0105901*
X0652641Y0105894*
X0652649Y0105871*
X065267Y010584*
X0652693Y0105793*
X0652703Y0105763*
X0652708Y0105755*
X0652724Y0105732*
X0652747Y0105685*
X0652757Y0105655*
X0652765Y0105644*
X0652778Y0105624*
X0652801Y0105577*
X0652808Y0105558*
X0652822Y0105545*
X0652857Y0105505*
X0652886Y0105462*
X0652909Y0105415*
X0652916Y0105395*
X065293Y0105383*
X0652965Y0105343*
X0652994Y0105299*
X0653017Y0105253*
X0653024Y0105233*
X0653039Y010522*
X0653064Y0105192*
X0653093Y0105166*
X0653118Y0105138*
X0653147Y0105112*
X0653172Y0105083*
X0653201Y0105058*
X0653226Y0105029*
X0653255Y0105004*
X065328Y0104975*
X0653298Y0104959*
X0653309Y010495*
X0653334Y0104921*
X0653363Y0104896*
X0653388Y0104867*
X0653417Y0104842*
X0653442Y0104813*
X065346Y0104797*
X0653471Y0104788*
X0653496Y0104759*
X0653525Y0104734*
X0653538Y0104719*
X0653557Y0104712*
X0653604Y0104689*
X0653648Y010466*
X0653687Y0104626*
X06537Y0104611*
X065372Y0104604*
X0653766Y0104581*
X065381Y0104552*
X065385Y0104517*
X0653862Y0104503*
X0653882Y0104496*
X0653929Y0104473*
X065396Y0104453*
X065399Y0104442*
X0654037Y0104419*
X0654068Y0104399*
X0654098Y0104388*
X0654145Y0104365*
X0654176Y0104344*
X0654206Y0104334*
X0654253Y0104311*
X0654284Y010429*
X0654314Y010428*
X0654361Y0104257*
X0654366Y0104254*
X0654375Y0104253*
X0654427Y0104243*
X0654476Y0104226*
X0654523Y0104203*
X0654528Y01042*
X0654537Y0104199*
X0654589Y0104189*
X0654639Y0104172*
X0654686Y0104149*
Y0104148*
X0654701*
X0654754Y0104145*
X0654805Y0104135*
X0654855Y0104118*
X0654902Y0104095*
Y0104094*
X0654972*
X0655024Y0104091*
X0655076Y0104081*
X0655125Y0104064*
X0655172Y0104041*
X0655173Y010404*
X0697735*
X0697762Y0104039*
X0697789Y010404*
X0697843*
X0697895Y0104037*
X0697947Y0104027*
X0697996Y010401*
X0698043Y0103987*
X0698044Y0103986*
X0698221*
X0698274Y0103983*
X0698325Y0103972*
X0698375Y0103956*
X0698422Y0103932*
X0698438*
X069849Y0103929*
X0698541Y0103919*
X0698591Y0103902*
X0698638Y0103878*
X0698643Y0103875*
X0698652*
X0698703Y0103864*
X0698753Y0103848*
X06988Y0103824*
X0698805Y0103821*
X0698814*
X0698866Y010381*
X0698915Y0103794*
X0698962Y010377*
X0698967Y0103767*
X0698977*
X0699028Y0103756*
X0699078Y0103739*
X0699125Y0103716*
X0699155Y0103696*
X0699186Y0103685*
X0699233Y0103662*
X0699263Y0103642*
X0699294Y0103631*
X0699341Y0103608*
X0699372Y0103587*
X0699391Y0103581*
X0699402Y0103577*
X0699449Y0103554*
X069948Y0103533*
X069951Y0103523*
X0699557Y01035*
X0699601Y0103471*
X069964Y0103436*
X0699653Y0103422*
X0699672Y0103415*
X0699719Y0103392*
X0699763Y0103363*
X0699802Y0103328*
X0699815Y0103314*
X0699834Y0103307*
X0699881Y0103284*
X0699925Y0103255*
X0699965Y010322*
X069999Y0103191*
X0700007Y0103176*
X0700019Y0103166*
X0700044Y0103137*
X0700073Y0103112*
X0700085Y0103097*
X0700105Y0103091*
X0700152Y0103068*
X0700195Y0103038*
X0700235Y0103004*
X070026Y0102975*
X0700289Y010295*
X0700314Y0102921*
X0700332Y0102905*
X0700343Y0102896*
X0700368Y0102867*
X0700397Y0102842*
X0700422Y0102813*
X0700448Y010279*
X0700451Y0102787*
X0700462Y0102774*
X0700476Y0102759*
X0700494Y0102743*
X0700505Y0102734*
X070054Y0102694*
X0700569Y010265*
X0700592Y0102603*
X0700598Y0102584*
X0700613Y0102571*
X0700638Y0102542*
X0700653Y010253*
X0700667Y0102517*
X0700693Y0102489*
X0700721Y0102463*
X0700756Y0102424*
X0700785Y010238*
X0700808Y0102333*
X0700815Y0102314*
X0700829Y0102301*
X0700864Y0102261*
X0700893Y0102218*
X0700916Y0102171*
X0700923Y0102152*
X0700938Y0102139*
X0700972Y0102099*
X0701001Y0102056*
X0701024Y0102009*
X0701035Y0101979*
X070105Y0101955*
X0701055Y0101948*
X0701079Y0101901*
X0701087Y0101874*
X0701089Y010187*
X0701109Y0101839*
X0701133Y0101793*
X0701142Y0101766*
X0701143Y0101762*
X0701163Y0101731*
X0701187Y0101684*
X0701203Y0101635*
X0701214Y0101583*
Y0101574*
X0701218Y0101569*
X0701241Y0101522*
X070125Y0101496*
X0701251Y0101492*
X0701272Y0101461*
X0701295Y0101414*
X0701312Y0101364*
X0701322Y0101313*
X0701323Y0101304*
X0701326Y0101299*
X0701349Y0101252*
X0701366Y0101202*
X0701376Y0101151*
X0701379Y0101099*
Y0101083*
X070138*
X0701403Y0101036*
X070142Y0100986*
X070143Y0100935*
X0701433Y0100882*
Y0100828*
Y0100813*
X0701434Y0100812*
X0701457Y0100765*
X0701474Y0100716*
X0701484Y0100664*
X0701487Y0100612*
Y0100558*
Y0100504*
Y010045*
Y0100396*
Y0100342*
Y0100287*
Y0100233*
Y0100179*
Y0100125*
Y0100071*
Y0100017*
Y0099963*
Y0099909*
Y0099855*
Y0099801*
Y0099747*
Y0099693*
Y0099639*
Y0099585*
X0701484Y0099532*
X0701474Y0099481*
X0701457Y0099431*
X0701434Y0099384*
X0701433*
Y0099369*
Y0099314*
X070143Y0099262*
X070142Y0099211*
X0701403Y0099161*
X070138Y0099114*
X0701379*
Y0099098*
X0701376Y0099046*
X0701366Y0098994*
X0701349Y0098945*
X0701326Y0098898*
X0701323Y0098893*
X0701322Y0098884*
X0701312Y0098832*
X0701295Y0098783*
X0701272Y0098736*
X0701268Y0098731*
Y0098721*
X0701258Y009867*
X0701241Y009862*
X0701218Y0098573*
X0701197Y0098543*
X0701191Y0098526*
X0701187Y0098512*
X0701163Y0098465*
X0701143Y0098434*
X0701133Y0098404*
X0701109Y0098357*
X0701089Y0098326*
X070108Y00983*
X0701079Y0098296*
X0701055Y0098249*
X0701035Y0098218*
X0701024Y0098188*
X0701001Y0098141*
X0700981Y009811*
X070097Y009808*
X0700947Y0098033*
X0700918Y0097989*
X0700883Y009795*
X0700869Y0097937*
X0700866Y0097928*
X0700862Y0097918*
X0700839Y0097871*
X070081Y0097827*
X0700775Y0097787*
X0700747Y0097762*
X0700721Y0097733*
X0700693Y0097708*
X0700667Y0097679*
X0700653Y0097667*
Y0097666*
X0700646Y0097647*
X0700623Y00976*
X0700594Y0097557*
X0700559Y0097517*
X070053Y0097492*
X0700515Y0097475*
X0700505Y0097463*
X0700476Y0097438*
X0700451Y0097409*
X0700422Y0097384*
X0700397Y0097355*
X0700368Y009733*
X0700343Y0097301*
X0700322Y0097283*
X0700314Y0097276*
X0700289Y0097247*
X070026Y0097222*
X0700235Y0097193*
X0700206Y0097168*
X0700181Y0097139*
X0700152Y0097114*
X0700127Y0097085*
X0700087Y009705*
X0700044Y0097021*
X0699997Y0096998*
X0699977Y0096991*
X0699965Y0096977*
X0699939Y0096955*
X0699936Y0096951*
X069991Y0096923*
X0699871Y0096888*
X0699827Y0096859*
X069978Y0096836*
X0699761Y0096829*
X0699748Y0096814*
X0699709Y009678*
X0699665Y0096751*
X0699618Y0096728*
X0699588Y0096717*
X0699579Y0096711*
X0699557Y0096697*
X069951Y0096674*
X0699491Y0096667*
X0699478Y0096652*
X0699438Y0096618*
X0699395Y0096588*
X0699348Y0096565*
X0699298Y0096548*
X0699247Y0096538*
X0699237*
X0699233Y0096535*
X0699186Y0096511*
X0699155Y0096501*
X0699125Y009648*
X0699078Y0096457*
X0699047Y0096447*
X0699038Y0096441*
X0699016Y0096426*
X0698969Y0096403*
X069892Y0096386*
X0698868Y0096376*
X0698859*
X0698854Y0096372*
X0698807Y0096349*
X0698758Y0096332*
X0698706Y0096322*
X0698697Y0096321*
X0698692Y0096318*
X0698645Y0096295*
X0698595Y0096278*
X0698544Y0096268*
X0698492Y0096264*
X0698476*
X0698429Y0096241*
X0698379Y0096224*
X0698328Y0096214*
X0698275Y009621*
X0698152*
X0698151*
X0698104Y0096187*
X0698055Y009617*
X0698003Y009616*
X0697951Y0096156*
X0670094*
X0670093*
X0670046Y0096133*
X0669997Y0096116*
X0669945Y0096106*
X0669893Y0096102*
X0669769*
X0669722Y0096079*
X0669672Y0096062*
X0669621Y0096052*
X0669568Y0096048*
X0669553*
X0669506Y0096025*
X0669456Y0096008*
X0669405Y0095998*
X0669352Y0095994*
X0669337*
X0669336*
X0669289Y0095971*
X0669259Y009596*
X0669228Y009594*
X0669181Y0095917*
X0669132Y00959*
X066908Y009589*
X0669071Y0095889*
X0669066Y0095886*
X0669019Y0095863*
X0668989Y0095852*
X0668958Y0095832*
X0668911Y0095809*
X0668881Y0095798*
X0668861Y0095785*
X066885Y0095778*
X0668803Y0095754*
X0668773Y0095744*
X0668742Y0095724*
X0668695Y00957*
X0668675Y0095694*
X0668663Y0095679*
X0668623Y0095645*
X0668579Y0095615*
X0668533Y0095592*
X0668513Y0095586*
X0668504Y0095575*
X06685Y0095571*
X0668471Y0095546*
X0668446Y0095517*
X0668407Y0095482*
X0668363Y0095453*
X0668316Y009543*
X0668297Y0095424*
X0668284Y0095409*
X0668255Y0095384*
X066823Y0095355*
X0668201Y0095329*
X0668176Y0095301*
X0668147Y0095275*
X0668122Y0095247*
X0668093Y0095221*
X0668068Y0095193*
X0668043Y0095171*
X0668039Y0095167*
X0668014Y0095139*
X0667985Y0095113*
X066796Y0095085*
X0667931Y0095059*
X0667906Y009503*
X0667877Y0095005*
X0667852Y0094976*
X0667837Y0094963*
X0667833Y0094951*
X066783Y0094944*
X0667807Y0094897*
X0667778Y0094854*
X0667743Y0094814*
X0667729Y0094801*
X0667722Y0094782*
X0667699Y0094735*
X066767Y0094691*
X0667635Y0094652*
X0667621Y0094639*
X0667614Y009462*
X0667591Y0094573*
X066757Y0094542*
X066756Y0094512*
X0667537Y0094465*
X0667516Y0094434*
X0667506Y0094404*
X0667483Y0094357*
X0667462Y0094326*
X0667452Y0094295*
X0667429Y0094248*
X0667408Y0094218*
X0667398Y0094187*
X0667375Y009414*
X0667372Y0094136*
X0667371Y0094126*
X0667361Y0094075*
X0667344Y0094025*
X0667321Y0093978*
X0667317Y0093973*
Y0093964*
X0667307Y0093913*
X066729Y0093863*
X0667267Y0093816*
X0667266Y0093815*
Y00938*
X0667263Y0093748*
X0667253Y0093696*
X0667236Y0093647*
X0667212Y00936*
Y0093599*
Y0093584*
Y009353*
Y0093476*
X0667209Y0093423*
X0667199Y0093372*
X0667182Y0093322*
X0667158Y0093275*
Y009326*
Y0093205*
Y0093151*
Y0093097*
Y0093043*
Y0092989*
Y0092935*
Y0092881*
Y0092827*
Y0092812*
Y0092811*
X0667182Y0092764*
X0667199Y0092715*
X0667209Y0092663*
X0667212Y0092611*
Y0092557*
Y0092503*
Y0092487*
X0667236Y009244*
X0667253Y009239*
X0667263Y0092339*
X0667266Y0092286*
Y0092271*
X0667267Y009227*
X066729Y0092224*
X0667307Y0092174*
X0667317Y0092122*
Y0092113*
X0667321Y0092108*
X0667344Y0092061*
X0667361Y0092012*
X0667371Y009196*
X0667372Y0091951*
X0667375Y0091946*
X0667398Y0091899*
X0667408Y0091869*
X0667429Y0091838*
X0667452Y0091791*
X0667462Y0091761*
X0667483Y009173*
X0667506Y0091683*
X0667516Y0091653*
X0667537Y0091622*
X066756Y0091575*
X066757Y0091545*
X0667591Y0091514*
X0667614Y0091467*
X0667621Y0091447*
X0667632Y0091437*
X0667635Y0091435*
X066767Y0091395*
X0667699Y0091351*
X0667722Y0091304*
X0667729Y0091285*
X0667743Y0091272*
X0667769Y0091243*
X0667798Y0091218*
X0667832Y0091179*
X0667861Y0091135*
X0667884Y0091088*
X0667891Y0091069*
X0667906Y0091056*
X0667931Y0091027*
X0667939Y009102*
X066796Y0091002*
X0667985Y0090973*
X0668014Y0090948*
X0668039Y0090919*
X0668057Y0090904*
X0668068Y0090894*
X0668093Y0090865*
X0668122Y009084*
X0668147Y0090811*
X0668161Y0090799*
X0668176Y0090786*
X0668201Y0090757*
X0668219Y0090741*
X066823Y0090732*
X0668243Y0090717*
X0668262Y0090711*
X0668309Y0090687*
X0668353Y0090658*
X0668392Y0090624*
X0668418Y0090595*
X0668446Y009057*
X0668459Y0090555*
X0668478Y0090548*
X0668526Y0090525*
X0668569Y0090496*
X0668609Y0090461*
X0668621Y0090447*
X0668641Y009044*
X0668688Y0090417*
X0668718Y0090396*
X0668749Y0090386*
X0668796Y0090363*
X0668839Y0090334*
X0668879Y0090299*
X0668892Y0090285*
X0668911Y0090278*
X0668958Y0090255*
X0668963Y0090252*
X0668972Y0090251*
X0669024Y0090241*
X0669073Y0090224*
X066912Y0090201*
X0669151Y009018*
X0669181Y009017*
X0669228Y0090147*
X0669233Y0090144*
X0669242Y0090143*
X0669294Y0090133*
X0669343Y0090116*
X066939Y0090093*
X0669395Y0090089*
X0669405*
X0669456Y0090079*
X0669506Y0090062*
X0669553Y0090039*
Y0090038*
X0669568*
X0669621Y0090035*
X0669672Y0090025*
X0669722Y0090008*
X0669769Y0089985*
Y0089984*
X0669947*
X0669999Y0089981*
X0670051Y008997*
X06701Y0089954*
X0670147Y008993*
X0670148*
X0680327*
X0680379Y0089927*
X0680431Y0089916*
X068048Y0089899*
X0680527Y0089876*
X0680528*
X0680597*
X0680649Y0089873*
X0680701Y0089862*
X0680751Y0089846*
X0680797Y0089822*
X0680798*
X0680813*
X0680866Y0089819*
X0680917Y0089808*
X0680967Y0089791*
X0681014Y0089768*
X0681018Y0089765*
X0681028Y0089764*
X0681079Y0089754*
X0681129Y0089737*
X0681176Y0089714*
X0681181Y0089711*
X068119Y008971*
X0681242Y00897*
X0681291Y0089683*
X0681338Y008966*
X0681343Y0089657*
X0681352Y0089656*
X0681404Y0089646*
X0681453Y0089629*
X06815Y0089606*
X0681531Y0089586*
X0681561Y0089575*
X0681608Y0089552*
X0681639Y0089531*
X068167Y0089521*
X0681717Y0089498*
X0681747Y0089477*
X0681778Y0089467*
X0681825Y0089444*
X0681855Y0089423*
X0681886Y0089413*
X0681933Y008939*
X0681976Y0089361*
X0682016Y0089326*
X0682027Y0089313*
X0682029Y0089311*
X0682048Y0089305*
X0682095Y0089282*
X0682139Y0089253*
X0682178Y0089218*
X0682197Y0089196*
X0682203Y0089189*
X0682217Y0089177*
X0682232Y0089164*
X0682245Y0089149*
X0682264Y0089143*
X0682311Y0089119*
X0682355Y008909*
X0682394Y0089056*
X0682419Y0089027*
X0682448Y0089002*
X0682474Y0088973*
X0682502Y0088948*
X0682522Y0088926*
X0682528Y0088919*
X0682546Y0088903*
X0682556Y0088894*
X0682582Y0088865*
X0682611Y008884*
X0682636Y0088811*
X0682662Y0088788*
X0682665Y0088785*
X068269Y0088757*
X0682719Y0088731*
X0682744Y0088703*
X0682773Y0088677*
X0682798Y0088649*
X0682816Y0088633*
X0682827Y0088623*
X0682852Y0088594*
X0682878Y0088572*
X0682881Y0088569*
X0682906Y008854*
X0682935Y0088515*
X068296Y0088486*
X0682986Y0088464*
X0682989Y0088461*
X0683024Y0088422*
X0683053Y0088378*
X0683076Y0088331*
X0683082Y0088312*
X0683097Y0088299*
X0683122Y008827*
X0683151Y0088245*
X0683186Y0088205*
X0683215Y0088162*
X0683238Y0088115*
X0683248Y0088085*
X0683269Y0088054*
X0683292Y0088007*
X0683299Y0087987*
X0683311Y0087977*
X0683313Y0087975*
X0683348Y0087935*
X0683377Y0087892*
X06834Y0087845*
X0683407Y0087825*
X0683411Y0087814*
X0683419Y0087801*
X0683431Y0087783*
X0683454Y0087736*
X0683463Y008771*
X0683465Y0087706*
X0683485Y0087675*
X0683508Y0087628*
X0683525Y0087579*
X0683535Y0087527*
X0683536Y0087518*
X0683539Y0087513*
X0683562Y0087466*
X0683572Y0087437*
X0683573Y0087436*
X0683577Y0087429*
X0683593Y0087405*
X0683616Y0087358*
X0683633Y0087308*
X0683644Y0087257*
Y0087248*
X0683647Y0087243*
X0683671Y0087196*
X0683687Y0087146*
X0683698Y0087095*
X0683701Y0087042*
Y0087027*
X0683725Y008698*
X0683742Y008693*
X0683752Y0086878*
X0683755Y0086826*
Y0086772*
Y0086757*
Y0086756*
X0683779Y0086709*
X0683795Y0086659*
X0683806Y0086608*
X0683809Y0086556*
Y0086502*
Y0086448*
Y0086394*
Y0086339*
Y0086286*
Y0086231*
Y0086177*
Y0086123*
Y0086069*
Y0086015*
Y0085961*
Y0085907*
Y0085853*
Y0085799*
Y0085745*
Y0085691*
Y0085637*
Y0085583*
Y0085529*
Y0085474*
Y0085421*
X0683806Y0085368*
X0683795Y0085317*
X0683779Y0085267*
X0683755Y008522*
Y0085204*
Y008515*
X0683752Y0085098*
X0683742Y0085046*
X0683725Y0084997*
X0683701Y008495*
X0683698Y0084945*
Y0084936*
X0683687Y0084884*
X0683671Y0084835*
X0683647Y0084788*
X0683644Y0084783*
Y0084773*
X0683633Y0084722*
X0683616Y0084672*
X0683593Y0084625*
X068359Y0084621*
Y0084611*
X0683579Y008456*
X0683562Y008451*
X0683539Y0084463*
X0683519Y0084432*
X0683508Y0084402*
X0683485Y0084355*
X0683465Y0084324*
X068346Y0084311*
X0683454Y0084294*
X0683431Y0084247*
X0683411Y0084216*
X06834Y0084186*
X0683377Y0084139*
X0683357Y0084108*
X0683356Y0084107*
X0683346Y0084078*
X0683323Y0084031*
X0683302Y0084*
X0683292Y008397*
X0683269Y0083923*
X068324Y0083879*
X0683205Y0083839*
X068319Y0083827*
X0683185Y0083812*
X0683184Y0083807*
X0683161Y008376*
X0683132Y0083717*
X0683097Y0083677*
X0683068Y0083652*
X0683043Y0083623*
X0683014Y0083598*
X0682989Y0083569*
X0682974Y0083556*
X0682968Y0083537*
X0682944Y008349*
X0682915Y0083447*
X0682881Y0083407*
X0682852Y0083382*
X0682827Y0083353*
X0682798Y0083328*
X0682773Y0083299*
X0682748Y0083277*
X0682744Y0083274*
X0682719Y0083245*
X0682694Y0083223*
X068269Y008322*
X0682665Y0083191*
X0682636Y0083166*
X0682611Y0083137*
X0682582Y0083112*
X0682556Y0083083*
X0682528Y0083057*
X0682502Y0083029*
X0682463Y0082994*
X0682419Y0082965*
X0682372Y0082942*
X0682353Y0082935*
X068234Y008292*
X0682311Y0082895*
X0682286Y0082866*
X0682247Y0082832*
X0682203Y0082803*
X0682156Y008278*
X0682137Y0082773*
X0682124Y0082758*
X0682085Y0082724*
X0682041Y0082695*
X0681994Y0082671*
X0681975Y0082665*
X0681962Y008265*
X0681922Y0082616*
X0681879Y0082586*
X0681832Y0082563*
X0681802Y0082553*
X0681785Y0082542*
X0681771Y0082532*
X0681724Y0082509*
X0681693Y0082499*
X0681663Y0082478*
X0681615Y0082455*
X0681585Y0082445*
X0681554Y0082424*
X0681507Y0082401*
X0681477Y0082391*
X0681446Y008237*
X0681399Y0082347*
X068135Y008233*
X0681298Y008232*
X0681289Y0082319*
X0681284Y0082316*
X0681237Y0082293*
X0681187Y0082276*
X0681136Y0082266*
X0681127Y0082265*
X0681122Y0082262*
X0681075Y0082239*
X0681025Y0082222*
X0680974Y0082212*
X0680965Y0082211*
X068096Y0082208*
X0680913Y0082185*
X0680863Y0082168*
X0680812Y0082158*
X0680759Y0082154*
X068069*
X0680689*
X0680642Y0082131*
X0680593Y0082114*
X0680541Y0082104*
X0680489Y00821*
X0680311*
X0680264Y0082077*
X0680214Y008206*
X0680163Y008205*
X0680111Y0082046*
X0680002*
X0679975Y0082048*
X0679948Y0082046*
X066373*
X0663703Y0082048*
X0663676Y0082046*
X0663336*
X0663288Y0082023*
X0663239Y0082006*
X0663187Y0081996*
X0663135Y0081992*
X0663066*
X0663065*
X0663018Y0081969*
X0662968Y0081952*
X0662917Y0081941*
X0662865Y0081938*
X066285*
X0662849*
X0662802Y0081915*
X0662752Y0081898*
X0662701Y0081888*
X0662691Y0081887*
X0662687Y0081884*
X066264Y0081861*
X0662609Y008185*
X0662601Y0081844*
X0662579Y008183*
X0662532Y0081806*
X0662482Y008179*
X066243Y0081779*
X0662421*
X0662416Y0081775*
X0662369Y0081752*
X0662339Y0081742*
X0662308Y0081722*
X0662261Y0081698*
X0662242Y0081692*
X0662229Y0081677*
X066219Y0081643*
X0662146Y0081613*
X0662099Y008159*
X0662069Y008158*
X0662038Y0081559*
X0661991Y0081536*
X0661972Y008153*
X0661959Y0081515*
X0661919Y008148*
X0661876Y0081451*
X0661829Y0081428*
X066181Y0081422*
X0661797Y0081407*
X0661768Y0081381*
X0661743Y0081353*
X0661714Y0081327*
X0661689Y0081299*
X0661649Y0081264*
X0661606Y0081235*
X0661558Y0081212*
X0661539Y0081205*
X0661526Y0081191*
X0661501Y0081169*
X0661498Y0081165*
X0661472Y0081137*
X0661444Y0081111*
X0661418Y0081082*
X0661404Y0081069*
X0661397Y008105*
X0661374Y0081003*
X0661345Y008096*
X066131Y008092*
X0661281Y0080895*
X0661256Y0080866*
X0661227Y0080841*
X0661202Y0080812*
X0661187Y0080799*
X0661186Y0080794*
X0661181Y008078*
X0661158Y0080733*
X0661128Y0080689*
X0661094Y008065*
X0661079Y0080637*
X0661073Y0080618*
X0661049Y0080571*
X066102Y0080527*
X0660986Y0080488*
X0660971Y0080475*
X0660964Y0080456*
X0660941Y0080409*
X0660921Y0080378*
X0660913Y0080354*
X0660911Y0080347*
X0660887Y00803*
X0660867Y008027*
X0660859Y0080246*
X0660856Y0080239*
X0660833Y0080192*
X0660813Y0080161*
X0660802Y0080131*
X0660779Y0080084*
X0660776Y0080079*
X0660775Y008007*
X0660765Y0080019*
X0660748Y0079969*
X0660725Y0079922*
X0660722Y0079917*
X0660721Y0079908*
X0660711Y0079856*
X0660694Y0079807*
X0660671Y007976*
X0660668Y0079755*
X0660667Y0079746*
X0660657Y0079694*
X066064Y0079645*
X0660617Y0079598*
Y0079597*
Y0079582*
Y0079528*
X0660613Y0079475*
X0660603Y0079424*
X0660586Y0079374*
X0660563Y0079327*
Y0079312*
Y0079257*
Y0079203*
Y0079149*
Y0079095*
Y0079041*
Y0078987*
Y0078933*
Y0078879*
Y0078825*
Y0078771*
Y0078717*
Y0078663*
Y0078609*
Y0078593*
X0660586Y0078546*
X0660603Y0078496*
X0660613Y0078445*
X0660617Y0078392*
Y0078338*
Y0078323*
Y0078322*
X066064Y0078276*
X0660657Y0078226*
X0660667Y0078174*
X0660668Y0078165*
X0660671Y007816*
X0660694Y0078113*
X0660711Y0078064*
X0660721Y0078012*
X0660722Y0078003*
X0660725Y0077998*
X0660748Y0077951*
X0660765Y0077902*
X0660775Y007785*
X0660776Y0077841*
X0660779Y0077836*
X0660802Y0077789*
X0660813Y0077759*
X0660833Y0077728*
X0660856Y0077681*
X0660867Y007765*
X0660887Y007762*
X0660911Y0077573*
X0660921Y0077542*
X0660928Y0077532*
X0660941Y0077512*
X0660964Y0077465*
X0660975Y0077434*
X0660995Y0077403*
X0661019Y0077356*
X0661025Y0077337*
X066104Y0077324*
X0661074Y0077285*
X0661103Y0077241*
X0661127Y0077194*
X0661131Y007718*
X0661133Y0077175*
X0661148Y0077162*
X0661173Y0077133*
X0661202Y0077108*
X0661237Y0077069*
X0661266Y0077025*
X0661289Y0076978*
X0661295Y0076959*
X066131Y0076946*
X0661335Y0076917*
X0661364Y0076892*
X0661383Y007687*
X0661389Y0076863*
X0661415Y007684*
X0661418Y0076838*
X0661444Y0076809*
X0661472Y0076784*
X0661498Y0076755*
X0661526Y007673*
X0661552Y0076701*
X0661577Y0076678*
X066158Y0076676*
X0661606Y0076647*
X0661634Y0076622*
X0661647Y0076607*
X0661667Y00766*
X0661714Y0076577*
X0661757Y0076548*
X0661797Y0076513*
X0661822Y0076485*
X0661851Y0076459*
X0661864Y0076445*
X0661883Y0076438*
X066193Y0076415*
X0661973Y0076386*
X0662013Y0076351*
X0662026Y0076336*
X0662028*
X0662045Y007633*
X0662092Y0076307*
X0662123Y0076286*
X0662153Y0076276*
X06622Y0076253*
X0662231Y0076232*
X0662261Y0076222*
X0662308Y0076199*
X0662339Y0076178*
X0662369Y0076168*
X0662416Y0076145*
X0662447Y0076124*
X0662477Y0076114*
X0662525Y0076091*
X0662529Y0076087*
X0662539*
X066259Y0076077*
X066264Y007606*
X0662687Y0076037*
X0662718Y0076016*
X0662748Y0076006*
X0662795Y0075982*
X0662811*
X0662863Y0075979*
X0662915Y0075968*
X0662964Y0075951*
X0663011Y0075928*
X0663012*
X0663081*
X0663133Y0075925*
X0663185Y0075914*
X0663234Y0075898*
X0663281Y0075874*
X0663282*
X0663568*
X066362Y0075871*
X0663671Y007586*
X0663721Y0075843*
X0663768Y007582*
X0674758*
X0674811Y0075816*
X0674862Y0075806*
X0674912Y0075789*
X0674959Y0075766*
X0675029*
X0675081Y0075762*
X0675133Y0075752*
X0675182Y0075735*
X0675229Y0075712*
X0675234Y0075709*
X0675243Y0075708*
X0675295Y0075698*
X0675344Y0075681*
X0675391Y0075658*
X0675396Y0075655*
X0675405Y0075654*
X0675457Y0075644*
X0675506Y0075627*
X0675554Y0075604*
X0675558Y0075601*
X0675568Y00756*
X0675619Y007559*
X0675669Y0075573*
X0675716Y007555*
X0675721Y0075547*
X067573Y0075546*
X0675781Y0075536*
X0675831Y0075519*
X0675878Y0075496*
X0675909Y0075475*
X0675939Y0075465*
X0675986Y0075442*
X0676017Y0075421*
X0676047Y0075411*
X0676094Y0075388*
X0676138Y0075359*
X0676177Y0075324*
X0676189Y0075311*
X067619Y0075309*
X0676209Y0075303*
X0676256Y007528*
X0676287Y0075259*
X0676317Y0075249*
X0676365Y0075226*
X0676408Y0075196*
X0676447Y0075162*
X067646Y0075147*
X067648Y0075141*
X0676527Y0075117*
X067657Y0075088*
X067661Y0075054*
X0676635Y0075025*
X0676664Y0075*
X0676689Y0074971*
X0676718Y0074946*
X0676731Y0074931*
X0676739Y0074928*
X067675Y0074924*
X0676797Y0074901*
X067684Y0074872*
X067688Y0074837*
X0676905Y0074809*
X0676934Y0074783*
X0676959Y0074755*
X0676988Y0074729*
X0677013Y00747*
X0677042Y0074675*
X0677067Y0074647*
X0677096Y0074621*
X0677121Y0074592*
X067715Y0074567*
X0677185Y0074528*
X0677214Y0074484*
X0677237Y0074437*
X0677244Y0074418*
X0677258Y0074405*
X0677284Y0074376*
X0677313Y0074351*
X0677338Y0074322*
X0677366Y0074297*
X0677401Y0074257*
X067743Y0074214*
X0677453Y0074167*
X067746Y0074148*
X0677475Y0074135*
X0677509Y0074095*
X0677538Y0074052*
X0677562Y0074005*
X0677568Y0073985*
X0677575Y0073979*
X0677583Y0073972*
X0677617Y0073933*
X0677646Y0073889*
X067767Y0073842*
X067768Y0073812*
X0677701Y0073781*
X0677724Y0073734*
X0677734Y0073704*
X0677755Y0073673*
X0677778Y0073626*
X0677785Y0073604*
X0677788Y0073596*
X0677804Y0073573*
X0677809Y0073565*
X0677832Y0073518*
X0677842Y0073488*
X0677863Y0073457*
X0677886Y007341*
X0677903Y007336*
X0677913Y0073309*
X0677914Y0073299*
X0677917Y0073295*
X067794Y0073248*
X0677957Y0073198*
X0677967Y0073147*
X0677968Y0073137*
X0677971Y0073133*
X0677994Y0073086*
X0678011Y0073036*
X0678021Y0072984*
X0678022Y0072975*
X0678025Y007297*
X0678048Y0072923*
X0678065Y0072874*
X0678075Y0072822*
X0678079Y007277*
Y0072716*
Y0072662*
Y0072647*
Y0072646*
X0678102Y0072599*
X0678119Y0072549*
X0678129Y0072498*
X0678133Y0072446*
Y0072391*
Y0072338*
Y0072283*
Y0072229*
Y0072175*
Y007216*
Y0072159*
X0678156Y0072113*
X0678173Y0072063*
X0678183Y0072011*
X0678187Y0071959*
Y0071905*
Y0071851*
X0678183Y0071799*
X0678173Y0071747*
X0678156Y0071697*
X0678133Y007165*
Y0071635*
Y0071581*
Y0071526*
Y0071473*
Y0071418*
Y0071364*
Y007131*
X0678129Y0071258*
X0678119Y0071207*
X0678102Y0071157*
X0678079Y007111*
Y0071109*
Y0071094*
Y007104*
X0678075Y0070988*
X0678065Y0070936*
X0678048Y0070887*
X0678025Y007084*
X0678022Y0070835*
X0678021Y0070825*
X0678011Y0070774*
X0677994Y0070724*
X0677971Y0070677*
X0677968Y0070673*
X0677967Y0070663*
X0677957Y0070612*
X067794Y0070562*
X0677917Y0070515*
X0677914Y0070511*
X0677913Y0070501*
X0677903Y007045*
X0677886Y00704*
X0677863Y0070353*
X067786Y0070348*
X0677859Y0070339*
X0677849Y0070288*
X0677832Y0070238*
X0677809Y0070191*
X0677788Y007016*
X0677778Y007013*
X0677755Y0070083*
X0677734Y0070052*
X0677724Y0070022*
X0677701Y0069975*
X067768Y0069944*
X067767Y0069914*
X0677646Y0069866*
X0677617Y0069823*
X0677583Y0069783*
X0677568Y0069771*
X0677562Y0069751*
X0677538Y0069704*
X0677509Y0069661*
X0677475Y0069621*
X067746Y0069608*
X0677453Y0069589*
X067743Y0069542*
X0677401Y0069498*
X0677366Y0069459*
X0677338Y0069434*
X0677313Y0069405*
X0677298Y0069392*
X0677291Y0069373*
X0677268Y0069326*
X0677239Y0069282*
X0677204Y0069243*
X0677176Y0069217*
X067715Y0069189*
X0677121Y0069164*
X0677096Y0069135*
X0677067Y0069109*
X0677042Y0069081*
X0677013Y0069055*
X0676988Y0069027*
X0676959Y0069001*
X0676947Y0068988*
X0676934Y0068972*
X0676905Y0068947*
X067688Y0068918*
X0676851Y0068893*
X0676826Y0068864*
X0676797Y0068839*
X0676772Y006881*
X0676743Y0068785*
X0676718Y0068756*
X0676689Y0068731*
X0676664Y0068702*
X0676624Y0068668*
X0676581Y0068638*
X0676534Y0068615*
X0676514Y0068609*
X0676502Y0068594*
X0676473Y0068569*
X0676453Y0068547*
X0676447Y006854*
X0676408Y0068505*
X0676365Y0068476*
X0676317Y0068453*
X0676298Y0068447*
X0676285Y0068432*
X0676246Y0068397*
X0676202Y0068368*
X0676155Y0068345*
X0676125Y0068335*
X0676094Y0068314*
X0676047Y0068291*
X0676017Y0068281*
X0675986Y006826*
X0675939Y0068237*
X0675909Y0068227*
X0675878Y0068206*
X0675831Y0068183*
X0675801Y0068173*
X067577Y0068152*
X0675723Y0068129*
X0675673Y0068112*
X0675622Y0068102*
X0675612Y0068101*
X0675608Y0068098*
X0675561Y0068075*
X0675511Y0068058*
X0675459Y0068048*
X0675407Y0068044*
X0675392*
X0675391*
X0675344Y0068021*
X0675295Y0068004*
X0675243Y0067993*
X0675191Y006799*
X0636467*
X063642Y0067967*
X06364Y006796*
X0636387Y0067945*
X0636373Y0067932*
X0636366Y0067913*
X0636343Y0067866*
Y006785*
Y0067796*
Y0067742*
Y0067688*
Y0067634*
Y006758*
Y0067526*
Y0067472*
Y0067418*
Y0067364*
Y006731*
Y0067256*
Y0067202*
Y0067147*
Y0067093*
Y0067039*
Y0066985*
Y0066931*
Y0066877*
Y0066823*
Y0066769*
Y0066715*
Y0066661*
Y0066607*
Y0066553*
Y0066499*
Y0066445*
Y0066391*
Y0066337*
Y0066282*
Y0066228*
Y0066174*
Y006612*
Y0066066*
Y0066012*
Y0065958*
Y0065904*
Y006585*
Y0065796*
Y0065742*
Y0065688*
Y0065634*
Y006558*
Y0065526*
Y0065472*
Y0065417*
Y0065364*
Y0065309*
Y0065255*
Y0065201*
Y0065147*
Y0065093*
Y0065039*
Y0064985*
Y0064931*
Y0064877*
Y0064823*
Y0064769*
Y0064715*
Y0064661*
Y0064607*
Y0064552*
Y0064499*
Y0064444*
Y006439*
Y0064336*
Y0064282*
Y0064228*
Y0064174*
Y006412*
Y0064066*
Y0064012*
Y0063958*
Y0063904*
Y006385*
Y0063796*
Y0063742*
Y0063688*
Y0063634*
Y0063579*
Y0063525*
Y0063471*
Y0063417*
Y0063363*
Y0063309*
Y0063255*
Y0063201*
Y0063147*
Y0063093*
Y0063039*
Y0062985*
Y0062931*
Y0062877*
Y0062823*
Y0062769*
Y0062714*
X0636339Y0062662*
X0636329Y0062611*
X0636312Y0062561*
X0636289Y0062514*
X0636268Y0062483*
X0636258Y0062453*
X0636235Y0062406*
X0636214Y0062375*
X0636204Y0062345*
X0636181Y0062298*
X0636152Y0062254*
X0636117Y0062215*
X0636088Y006219*
X0636063Y0062161*
X0636024Y0062126*
X063598Y0062097*
X0635933Y0062074*
X0635903Y0062063*
X0635872Y0062043*
X0635825Y006202*
X0635795Y0062009*
X0635764Y0061989*
X0635717Y0061966*
X0635667Y0061949*
X0635616Y0061939*
X0635564Y0061935*
X0625238*
X0625185Y0061939*
X0625134Y0061949*
X0625084Y0061966*
X0625037Y0061989*
X0625032Y0061992*
X0625023Y0061993*
X0624972Y0062003*
X0624922Y006202*
X0624875Y0062043*
X0624831Y0062072*
X0624792Y0062107*
X0624767Y0062135*
X0624738Y0062161*
X0624713Y006219*
X0624684Y0062215*
X0624659Y0062244*
X062463Y0062269*
X0624595Y0062308*
X0624566Y0062352*
X0624543Y0062399*
X0624533Y0062429*
X0624512Y006246*
X0624489Y0062507*
X0624472Y0062557*
X0624462Y0062608*
X0624458Y006266*
Y0062714*
Y0062769*
Y0062823*
Y0062877*
Y0062931*
Y0062985*
Y0063039*
Y0063093*
Y0063147*
Y0063201*
Y0063255*
Y0063309*
Y0063363*
Y0063417*
Y0063471*
Y0063525*
Y0063579*
Y0063634*
Y0063688*
Y0063742*
Y0063796*
Y006385*
Y0063904*
Y0063958*
Y0064012*
Y0064066*
Y006412*
Y0064174*
Y0064228*
Y0064282*
Y0064336*
Y006439*
Y0064444*
Y0064499*
Y0064552*
Y0064607*
Y0064661*
Y0064715*
Y0064769*
Y0064823*
Y0064877*
Y0064931*
Y0064985*
Y0065039*
Y0065093*
Y0065147*
Y0065201*
Y0065255*
Y0065309*
Y0065364*
Y0065417*
Y0065472*
Y0065526*
Y006558*
Y0065634*
Y0065688*
Y0065742*
Y0065757*
Y0065758*
X0624435Y0065805*
X0624418Y0065854*
X0624408Y0065906*
X0624407Y0065915*
X0624404Y006592*
X0624399Y006593*
X0624388Y0065935*
X0624384Y0065939*
X0624374*
X0624346Y0065945*
X0624327Y0065941*
X0624303Y006592*
X0624287Y0065901*
X0624284Y0065852*
X0624273Y00658*
X0624256Y0065751*
X0624233Y0065704*
Y0065703*
Y0065688*
Y0065634*
Y006558*
Y0065526*
Y0065472*
Y0065417*
Y0065364*
Y0065309*
Y0065255*
Y0065201*
Y0065147*
Y0065093*
Y0065039*
Y0064985*
Y0064931*
Y0064877*
Y0064823*
Y0064769*
Y0064715*
Y0064661*
Y0064607*
Y0064552*
Y0064499*
Y0064444*
Y006439*
Y0064336*
Y0064282*
Y0064228*
Y0064174*
Y006412*
Y0064066*
Y0064012*
Y0063958*
Y0063904*
Y006385*
Y0063796*
Y0063742*
Y0063688*
Y0063634*
Y0063579*
Y0063525*
Y0063471*
Y0063417*
Y0063363*
Y0063309*
Y0063255*
Y0063201*
Y0063147*
Y0063093*
Y0063039*
Y0062985*
Y0062931*
Y0062877*
Y0062823*
Y0062769*
Y0062714*
Y006266*
Y0062606*
X0624229Y0062554*
X0624219Y0062503*
X0624202Y0062453*
X0624179Y0062406*
X062415Y0062362*
X0624115Y0062323*
X0624087Y0062298*
X0624061Y0062269*
X0624033Y0062244*
X0624007Y0062215*
X0623979Y006219*
X0623953Y0062161*
X0623924Y0062135*
X0623899Y0062107*
X062386Y0062072*
X0623816Y0062043*
X0623769Y006202*
X062372Y0062003*
X0623668Y0061993*
X0623659Y0061992*
X0623654Y0061989*
X0623607Y0061966*
X0623557Y0061949*
X0623506Y0061939*
X0623454Y0061935*
X0618155*
X0618103Y0061939*
X0618052Y0061949*
X0618002Y0061966*
X0617955Y0061989*
X0617924Y0062009*
X0617894Y006202*
X0617847Y0062043*
X0617816Y0062063*
X0617786Y0062074*
X0617739Y0062097*
X0617695Y0062126*
X0617656Y0062161*
X0617631Y0062189*
X0617602Y0062215*
X0617567Y0062254*
X0617538Y0062298*
X0617515Y0062345*
X0617505Y0062375*
X0617484Y0062406*
X0617461Y0062453*
X0617444Y0062503*
X0617434Y0062554*
X0617433Y0062561*
Y0062563*
X061743Y0062568*
X0617407Y0062615*
X061739Y0062665*
X061738Y0062716*
X0617376Y0062769*
Y0062823*
Y0062877*
Y0062931*
Y0062985*
Y0063039*
Y0063093*
Y0063147*
Y0063201*
Y0063255*
Y0063309*
Y0063363*
Y0063417*
Y0063471*
Y0063525*
Y0063579*
Y0063634*
Y0063688*
Y0063742*
Y0063796*
Y006385*
Y0063904*
Y0063958*
Y0064012*
Y0064066*
Y006412*
Y0064174*
Y0064228*
Y0064282*
Y0064336*
Y006439*
Y0064444*
Y0064499*
Y0064552*
Y0064607*
Y0064661*
Y0064715*
Y0064769*
Y0064823*
Y0064877*
Y0064931*
Y0064985*
Y0065039*
Y0065093*
Y0065147*
Y0065201*
Y0065255*
Y0065309*
Y0065364*
Y0065417*
Y0065472*
Y0065526*
Y006558*
Y0065634*
Y0065688*
Y0065742*
Y0065796*
Y006585*
Y0065904*
Y0065958*
Y0066012*
Y0066066*
Y006612*
Y0066174*
Y0066228*
Y0066282*
Y0066337*
Y0066391*
Y0066445*
Y0066499*
Y0066553*
Y0066607*
Y0066661*
Y0066715*
Y0066769*
Y0066823*
Y0066877*
Y0066931*
Y0066985*
Y0067039*
Y0067093*
Y0067147*
X0617378Y0067175*
X0617376Y0067202*
Y0067256*
Y006731*
Y0067364*
Y0067418*
Y0067472*
Y0067487*
Y0067488*
X0617353Y0067535*
X0617348Y0067549*
X0617342Y0067565*
X0617322Y0067596*
X0617299Y0067643*
X0617292Y0067661*
X0617288Y0067673*
X0617268Y0067704*
X0617244Y0067751*
X0617238Y006777*
X0617223Y0067783*
X0617198Y0067812*
X0617169Y0067837*
X0617156Y0067852*
X0617137Y0067858*
X061709Y0067882*
X0617059Y0067902*
X0617029Y0067913*
X0616982Y0067936*
X0616977Y0067939*
X0616968Y006794*
X0616916Y006795*
X0616867Y0067967*
X061682Y006799*
X0616819*
X0616789*
X0616788*
X0616741Y0067967*
X0616691Y006795*
X061664Y006794*
X0616631Y0067939*
X0616626Y0067936*
X0616579Y0067913*
X0616549Y0067902*
X0616539Y0067896*
X0616518Y0067882*
X0616471Y0067858*
X0616452Y0067852*
X0616439Y0067837*
X061641Y0067812*
X0616385Y0067783*
X0616356Y0067758*
X061633Y0067729*
X0616316Y0067716*
X0616312Y0067704*
X0616309Y0067697*
X0616286Y006765*
X0616265Y0067619*
Y0067618*
X0616255Y0067589*
X0616232Y0067542*
Y0067541*
Y0067526*
Y0067472*
Y0067418*
X061623Y0067391*
X0616232Y0067364*
Y006731*
Y0067256*
X061623Y0067229*
X0616232Y0067202*
Y0067147*
Y0067093*
Y0067039*
Y0066985*
Y0066931*
Y0066877*
Y0066823*
Y0066769*
Y0066715*
Y0066661*
Y0066607*
Y0066553*
Y0066499*
Y0066445*
Y0066391*
Y0066337*
Y0066282*
Y0066228*
Y0066174*
Y006612*
Y0066066*
Y0066012*
Y0065958*
Y0065904*
Y006585*
Y0065796*
Y0065742*
Y0065688*
Y0065634*
Y006558*
Y0065526*
Y0065472*
Y0065417*
Y0065364*
Y0065309*
Y0065255*
Y0065201*
Y0065147*
Y0065093*
Y0065039*
Y0064985*
Y0064931*
Y0064877*
X0616228Y0064825*
X0616218Y0064773*
X0616201Y0064723*
X0616178Y0064676*
Y0064661*
X0616174Y0064608*
X0616164Y0064557*
X0616147Y0064507*
X0616124Y006446*
X0616095Y0064417*
X061606Y0064377*
X0616031Y0064352*
X0616006Y0064323*
X0615977Y0064298*
X0615952Y0064269*
X0615923Y0064244*
X0615898Y0064215*
X0615869Y006419*
X0615844Y0064161*
X0615804Y0064126*
X0615761Y0064097*
X0615714Y0064074*
X0615664Y0064057*
X0615613Y0064047*
X0615603Y0064046*
X0615599Y0064043*
X0615552Y006402*
X0615502Y0064003*
X0615451Y0063993*
X0615398Y006399*
X0612155*
X0612102Y0063993*
X0612051Y0064003*
X0612001Y006402*
X0611954Y0064043*
X0611949Y0064046*
X061194Y0064047*
X0611889Y0064057*
X0611839Y0064074*
X0611792Y0064097*
X0611748Y0064126*
X0611709Y0064161*
X061169Y0064183*
X0611684Y006419*
X0611655Y0064215*
X061163Y0064244*
X0611601Y0064269*
X0611576Y0064298*
X0611547Y0064323*
X0611521Y0064352*
X0611493Y0064377*
X0611458Y0064417*
X0611429Y006446*
X0611406Y0064507*
X0611389Y0064557*
X0611379Y0064608*
X0611378Y0064618*
X0611375Y0064622*
X0611352Y006467*
X0611335Y0064719*
X0611325Y0064771*
X0611321Y0064823*
Y0064877*
Y0064931*
Y0064985*
Y0065039*
Y0065093*
Y0065147*
Y0065201*
Y0065255*
Y0065309*
Y0065364*
Y0065417*
Y0065472*
Y0065526*
Y006558*
Y0065634*
Y0065688*
Y0065742*
Y0065796*
Y006585*
Y0065904*
Y0065958*
Y0066012*
Y0066066*
Y006612*
Y0066174*
Y0066228*
Y0066282*
Y0066337*
Y0066391*
Y0066445*
Y0066499*
Y0066553*
Y0066607*
Y0066661*
Y0066715*
Y0066769*
Y0066823*
Y0066877*
Y0066931*
Y0066985*
Y0067039*
Y0067093*
Y0067147*
Y0067202*
Y0067256*
Y006731*
Y0067364*
Y0067418*
Y0067472*
Y0067526*
Y006758*
X0611325Y0067632*
Y0067634*
Y0067636*
X0611321Y0067688*
Y0067742*
X0611323Y0067769*
X0611321Y0067796*
Y006785*
Y0067904*
Y006792*
X0611316Y0067931*
X0611305Y0067936*
X0611275Y0067956*
X0611244Y0067967*
X0611197Y006799*
X0603219*
X0603171Y0067967*
X0603152Y006796*
X0603139Y0067945*
X0603125Y0067932*
X0603118Y0067913*
X0603095Y0067866*
Y006785*
Y0067796*
Y0067742*
Y0067688*
Y0067634*
Y006758*
Y0067526*
Y0067472*
Y0067418*
Y0067364*
Y006731*
Y0067256*
Y0067202*
Y0067147*
Y0067093*
Y0067039*
Y0066985*
Y0066931*
Y0066877*
Y0066823*
Y0066769*
Y0066715*
Y0066661*
Y0066607*
Y0066553*
Y0066499*
Y0066445*
Y0066391*
Y0066337*
Y0066282*
Y0066228*
Y0066174*
Y006612*
Y0066066*
Y0066012*
Y0065958*
Y0065904*
Y006585*
Y0065796*
Y0065742*
Y0065688*
Y0065634*
Y006558*
Y0065526*
Y0065472*
Y0065417*
Y0065364*
Y0065309*
Y0065255*
Y0065201*
Y0065147*
Y0065093*
Y0065039*
Y0064985*
Y0064931*
Y0064877*
Y0064823*
Y0064769*
Y0064715*
Y0064661*
Y0064607*
Y0064552*
Y0064499*
Y0064444*
Y006439*
Y0064336*
Y0064282*
Y0064228*
Y0064174*
Y006412*
Y0064066*
Y0064012*
Y0063958*
Y0063904*
Y006385*
Y0063796*
Y0063742*
Y0063688*
Y0063634*
Y0063579*
Y0063525*
Y0063471*
Y0063417*
Y0063363*
X0603091Y0063311*
X0603081Y0063259*
X0603064Y006321*
X0603041Y0063163*
X0603012Y0063119*
X0602977Y006308*
X0602938Y0063045*
X0602894Y0063016*
X0602847Y0062993*
X0602798Y0062976*
X0602746Y0062966*
X0602694Y0062962*
X0594638*
X0594586Y0062966*
X0594535Y0062976*
X0594485Y0062993*
X0594438Y0063016*
X0594394Y0063045*
X0594355Y006308*
X059432Y0063119*
X0594291Y0063163*
X0594268Y006321*
X0594251Y0063259*
X0594241Y0063311*
X0594238Y0063363*
Y0063417*
Y0063471*
Y0063525*
Y0063579*
Y0063634*
Y0063688*
Y0063742*
Y0063796*
Y006385*
Y0063904*
Y0063958*
Y0064012*
Y0064066*
Y006412*
Y0064174*
Y0064228*
Y0064282*
Y0064336*
Y006439*
Y0064444*
Y0064499*
Y0064552*
Y0064607*
Y0064661*
Y0064715*
Y0064769*
Y0064823*
Y0064877*
Y0064931*
Y0064985*
Y0065039*
Y0065093*
Y0065147*
Y0065201*
Y0065255*
Y0065309*
Y0065364*
Y0065417*
Y0065472*
Y0065526*
Y006558*
Y0065634*
Y0065688*
Y0065742*
Y0065796*
Y006585*
Y0065904*
Y0065958*
Y0066012*
Y0066066*
Y006612*
Y0066174*
Y0066228*
Y0066282*
Y0066337*
Y0066391*
Y0066445*
Y0066499*
Y0066553*
Y0066607*
Y0066661*
Y0066715*
Y0066769*
Y0066823*
Y0066877*
Y0066931*
Y0066985*
Y0067039*
Y0067093*
Y0067147*
Y0067202*
Y0067256*
Y006731*
Y0067364*
Y0067418*
Y0067472*
Y0067526*
Y006758*
Y0067634*
Y0067688*
Y0067742*
Y0067796*
Y006785*
Y0067904*
Y0067958*
Y0068012*
Y0068067*
Y0068121*
Y0068175*
Y0068229*
X0594241Y0068281*
X0594251Y0068332*
X0594268Y0068382*
X0594291Y0068429*
X059432Y0068473*
X0594355Y0068512*
X0594394Y0068547*
X0594438Y0068576*
X0594485Y0068599*
X0594535Y0068616*
X0594586Y0068626*
X0594638Y006863*
X0599482*
Y0068661*
Y0068715*
Y0068769*
Y0068823*
Y0068878*
Y0068932*
Y0068986*
Y006904*
Y0069094*
Y0069148*
Y0069202*
Y0069256*
Y006931*
Y0069364*
Y0069418*
Y0069472*
Y0069526*
Y006958*
Y0069634*
Y0069688*
Y0069743*
Y0069797*
Y0069851*
Y0069905*
Y0069959*
Y0070013*
Y0070067*
Y0070121*
Y0070175*
Y0070229*
Y0070283*
Y0070337*
Y0070391*
Y0070445*
Y0070499*
Y0070553*
Y0070608*
Y0070662*
Y0070716*
Y007077*
Y0070824*
Y0070878*
Y0070932*
Y0070986*
Y007104*
Y0071094*
Y0071148*
Y0071202*
Y0071256*
Y007131*
Y0071364*
Y0071418*
Y0071473*
Y0071526*
Y0071581*
Y0071635*
Y0071689*
Y0071743*
Y0071797*
Y0071851*
Y0071905*
Y0071959*
Y0072013*
Y0072067*
Y0072121*
Y0072175*
Y0072229*
Y0072283*
Y0072338*
Y0072391*
Y0072446*
Y00725*
Y0072554*
Y0072608*
Y0072662*
Y0072716*
Y007277*
Y0072824*
Y0072878*
Y0072932*
Y0072986*
Y007304*
Y0073094*
Y0073148*
Y0073203*
Y0073256*
Y0073311*
Y0073365*
Y0073419*
Y0073473*
Y0073527*
Y0073581*
Y0073635*
Y0073689*
Y0073743*
Y0073775*
X0594638*
X0594586Y0073778*
X0594535Y0073788*
X0594485Y0073805*
X0594438Y0073828*
X0594394Y0073858*
X0594355Y0073892*
X059432Y0073932*
X0594291Y0073975*
X0594268Y0074022*
X0594251Y0074072*
X0594241Y0074123*
X0594238Y0074176*
Y007423*
Y0074284*
Y0074338*
Y0074392*
Y0074446*
Y00745*
Y0074554*
Y0074608*
Y0074662*
Y0074716*
Y007477*
Y0074824*
Y0074878*
Y0074932*
Y0074986*
Y0075041*
Y0075095*
Y0075149*
Y0075203*
Y0075257*
Y0075311*
Y0075365*
Y0075419*
Y0075473*
Y0075527*
X0594241Y007558*
X0594251Y0075631*
X0594268Y0075681*
X0594291Y0075728*
X059432Y0075771*
X0594355Y0075811*
X0594394Y0075845*
X0594438Y0075874*
X0594485Y0075898*
X0594535Y0075914*
X0594586Y0075925*
X0594638Y0075928*
X0599482*
Y007596*
Y0076014*
Y0076068*
Y0076122*
Y0076176*
Y007623*
Y0076284*
Y0076338*
Y0076392*
Y0076446*
Y00765*
Y0076554*
Y0076608*
Y0076662*
Y0076717*
Y0076771*
Y0076825*
Y0076879*
Y0076933*
Y0076987*
Y0077041*
Y0077095*
Y0077149*
Y0077203*
Y0077257*
Y0077311*
Y0077365*
Y0077419*
Y0077473*
Y0077527*
Y0077582*
Y0077636*
Y007769*
Y0077744*
Y0077798*
Y0077852*
Y0077906*
Y007796*
Y0078014*
Y0078068*
Y0078122*
Y0078176*
Y007823*
Y0078284*
Y0078338*
Y0078392*
Y0078447*
Y00785*
Y0078555*
Y0078609*
Y0078663*
Y0078717*
Y0078771*
Y0078825*
Y0078879*
Y0078933*
Y0078987*
Y0079041*
Y0079095*
Y0079149*
Y0079203*
Y0079257*
Y0079312*
Y0079365*
Y007942*
Y0079474*
Y0079528*
Y0079582*
Y0079636*
Y007969*
Y0079744*
Y0079798*
Y0079852*
Y0079906*
Y007996*
Y0080014*
Y0080068*
Y0080122*
Y0080177*
Y008023*
Y0080285*
Y0080339*
Y0080393*
Y0080447*
Y0080501*
Y0080555*
Y0080609*
Y0080663*
Y0080717*
Y0080771*
Y0080825*
Y0080879*
Y0080933*
Y0080987*
Y0081042*
Y0081073*
X0594693*
X059464Y0081077*
X0594589Y0081087*
X0594539Y0081104*
X0594492Y0081127*
X0594449Y0081156*
X0594409Y0081191*
X0594384Y0081219*
X0594355Y0081245*
X059432Y0081284*
X0594291Y0081328*
X0594268Y0081375*
X0594251Y0081424*
X0594241Y0081476*
X0594238Y0081528*
Y0081582*
Y0081636*
Y008169*
Y0081744*
Y0081798*
Y0081852*
Y0081906*
Y008196*
Y0082015*
Y0082069*
Y0082123*
Y0082177*
Y0082231*
Y0082285*
Y0082339*
Y0082393*
Y0082447*
Y0082501*
Y0082555*
Y0082609*
Y0082663*
Y0082717*
Y0082771*
Y0082825*
X0594241Y0082878*
X0594251Y0082929*
X0594268Y0082979*
X0594291Y0083026*
X059432Y0083069*
X0594355Y0083109*
X0594394Y0083144*
X0594438Y0083173*
X0594485Y0083196*
X0594535Y0083213*
X0594586Y0083223*
X0594638Y0083226*
X0599482*
Y0083258*
Y0083312*
Y0083366*
Y008342*
Y0083474*
Y0083528*
Y0083582*
Y0083636*
Y0083691*
Y0083745*
Y0083799*
Y0083853*
Y0083907*
Y0083961*
Y0084015*
Y0084069*
Y0084123*
Y0084177*
Y0084231*
Y0084285*
Y0084339*
Y0084393*
Y0084447*
Y0084501*
Y0084556*
Y008461*
Y0084664*
Y0084718*
Y0084772*
Y0084826*
Y008488*
Y0084934*
Y0084988*
Y0085042*
Y0085096*
Y008515*
Y0085204*
Y0085258*
Y0085312*
Y0085366*
Y0085421*
Y0085474*
Y0085529*
Y0085583*
Y0085637*
Y0085691*
Y0085745*
Y0085799*
Y0085853*
Y0085907*
Y0085961*
Y0086015*
Y0086069*
Y0086123*
Y0086177*
Y0086231*
Y0086286*
Y0086339*
Y0086394*
Y0086448*
Y0086502*
Y0086556*
Y008661*
Y0086664*
Y0086718*
Y0086772*
Y0086826*
Y008688*
Y0086934*
Y0086988*
Y0087042*
Y0087096*
Y0087151*
Y0087204*
Y0087259*
Y0087313*
Y0087367*
Y0087421*
Y0087475*
Y0087529*
Y0087583*
Y0087637*
Y0087691*
Y0087745*
Y0087799*
Y0087853*
Y0087907*
Y0087961*
Y0088016*
Y0088069*
Y0088124*
Y0088178*
Y0088232*
Y0088286*
Y008834*
Y0088394*
Y0088425*
X0594638*
X0594586Y0088429*
X0594535Y0088439*
X0594485Y0088456*
X0594438Y0088479*
X0594394Y0088508*
X0594355Y0088543*
X059432Y0088582*
X0594291Y0088626*
X0594268Y0088673*
X0594251Y0088723*
X0594241Y0088774*
X0594238Y0088826*
Y008888*
Y0088934*
Y0088989*
Y0089043*
Y0089097*
Y0089151*
Y0089205*
Y0089259*
Y0089313*
Y0089367*
Y0089421*
Y0089475*
Y0089529*
Y0089583*
Y0089637*
Y0089691*
Y0089745*
Y0089799*
Y0089854*
Y0089908*
Y0089962*
Y0090016*
Y009007*
Y0090124*
X0594241Y0090176*
X0594251Y0090228*
X0594268Y0090277*
X0594291Y0090324*
X059432Y0090368*
X0594355Y0090407*
X0594384Y0090433*
X0594409Y0090461*
X0594449Y0090496*
X0594492Y0090525*
X0594539Y0090548*
X0594589Y0090565*
X059464Y0090575*
X0594693Y0090579*
X0599482*
Y009061*
Y0090664*
Y0090719*
Y0090773*
Y0090827*
Y0090881*
Y0090935*
Y0090989*
Y0091043*
Y0091097*
Y0091151*
Y0091205*
Y0091259*
Y0091313*
Y0091367*
Y0091421*
Y0091475*
Y009153*
Y0091584*
Y0091638*
Y0091692*
Y0091746*
Y00918*
Y0091854*
Y0091908*
Y0091962*
Y0092016*
Y009207*
Y0092124*
Y0092178*
Y0092232*
Y0092286*
Y009234*
Y0092395*
Y0092449*
Y0092503*
Y0092557*
Y0092611*
Y0092665*
Y0092719*
Y0092773*
Y0092827*
Y0092881*
Y0092935*
Y0092989*
Y0093043*
Y0093097*
Y0093151*
Y0093205*
Y009326*
Y0093313*
Y0093368*
Y0093422*
Y0093476*
Y009353*
Y0093584*
Y0093638*
Y0093692*
Y0093746*
Y00938*
Y0093854*
Y0093908*
Y0093962*
Y0094016*
Y009407*
Y0094125*
Y0094178*
Y0094233*
Y0094287*
Y0094341*
Y0094395*
Y0094449*
Y0094503*
Y0094557*
Y0094611*
Y0094665*
Y0094719*
Y0094773*
Y0094827*
Y0094881*
Y0094935*
Y009499*
Y0095043*
Y0095098*
Y0095152*
Y0095206*
Y009526*
Y0095314*
Y0095368*
Y0095422*
Y0095476*
Y009553*
Y0095584*
Y0095638*
Y0095692*
Y0095724*
X0594638*
X0594586Y0095727*
X0594535Y0095738*
X0594485Y0095754*
X0594438Y0095778*
X0594394Y0095807*
X0594355Y0095841*
X059432Y0095881*
X0594291Y0095924*
X0594268Y0095971*
X0594251Y0096021*
X0594241Y0096072*
X0594238Y0096125*
Y0096179*
Y0096233*
Y0096287*
Y0096341*
Y0096395*
Y0096449*
Y0096503*
Y0096557*
Y0096611*
Y0096665*
Y0096719*
Y0096773*
Y0096828*
Y0096882*
Y0096936*
Y009699*
Y0097044*
Y0097098*
Y0097152*
Y0097206*
Y009726*
Y0097314*
Y0097368*
Y0097422*
Y0097476*
Y009753*
Y0097584*
Y0097638*
Y0097693*
Y0097747*
Y0097801*
Y0097855*
Y0097909*
Y0097963*
Y0098017*
Y0098071*
Y0098125*
Y0098179*
Y0098233*
Y0098287*
Y0098341*
Y0098395*
Y0098449*
Y0098504*
Y0098558*
Y0098612*
Y0098666*
Y009872*
Y0098774*
Y0098828*
Y0098882*
Y0098936*
Y009899*
Y0099044*
Y0099098*
Y0099152*
Y0099206*
Y009926*
Y0099314*
Y0099369*
Y0099423*
Y0099477*
Y0099531*
Y0099585*
Y0099639*
Y0099693*
Y0099747*
Y0099801*
Y0099855*
Y0099909*
Y0099963*
Y0100017*
Y0100071*
Y0100125*
Y0100179*
Y0100233*
Y0100287*
Y0100342*
Y0100396*
Y010045*
Y0100504*
Y0100558*
Y0100612*
Y0100666*
Y010072*
Y0100774*
Y0100828*
Y0100882*
Y0100936*
Y010099*
Y0101044*
Y0101099*
Y0101153*
Y0101207*
Y0101261*
Y0101315*
Y0101369*
Y0101423*
Y0101477*
Y0101531*
Y0101585*
Y0101639*
Y0101693*
Y0101747*
Y0101801*
Y0101855*
Y0101909*
Y0101963*
Y0102017*
Y0102072*
Y0102126*
Y010218*
Y0102234*
Y0102288*
Y0102342*
Y0102396*
Y010245*
Y0102504*
Y0102558*
Y0102612*
Y0102666*
Y010272*
Y0102774*
Y0102828*
Y0102883*
Y0102937*
Y0102991*
Y0103045*
Y0103099*
Y0103153*
Y0103207*
Y0103261*
Y0103315*
Y0103369*
Y0103423*
Y0103477*
Y0103531*
Y0103585*
Y0103639*
Y0103693*
Y0103747*
Y0103802*
Y0103856*
Y010391*
Y0103964*
Y0104018*
Y0104072*
Y0104126*
Y010418*
Y0104234*
Y0104288*
Y0104342*
Y0104396*
Y010445*
Y0104504*
Y0104558*
Y0104613*
Y0104667*
Y0104721*
Y0104775*
Y0104829*
Y0104883*
Y0104937*
Y0104991*
Y0105045*
Y0105099*
Y0105153*
Y0105207*
Y0105261*
Y0105315*
Y0105369*
Y0105423*
Y0105477*
Y0105532*
Y0105586*
Y010564*
Y0105694*
Y0105748*
Y0105802*
Y0105856*
Y010591*
Y0105964*
Y0106018*
Y0106072*
Y0106126*
Y010618*
Y0106234*
Y0106288*
Y0106342*
Y0106397*
Y0106451*
Y0106505*
Y0106559*
Y0106613*
Y0106667*
Y0106721*
Y0106775*
Y0106829*
Y0106883*
Y0106937*
Y0106991*
Y0107045*
Y0107099*
Y0107153*
Y0107208*
Y0107262*
Y0107316*
Y010737*
Y0107424*
Y0107478*
Y0107532*
Y0107586*
Y010764*
Y0107694*
Y0107748*
Y0107802*
Y0107856*
Y010791*
Y0107964*
Y0108018*
Y0108072*
Y0108126*
Y0108181*
Y0108235*
Y0108289*
Y0108343*
Y0108397*
Y0108451*
Y0108505*
Y0108559*
Y0108613*
Y0108667*
Y0108721*
Y0108775*
Y0108829*
Y0108883*
Y0108938*
Y0108992*
Y0109046*
Y01091*
Y0109154*
Y0109208*
Y0109262*
Y0109316*
Y010937*
Y0109424*
Y0109478*
Y0109532*
Y0109586*
Y010964*
Y0109694*
Y0109748*
Y0109802*
Y0109856*
Y0109911*
Y0109965*
Y0110019*
Y0110073*
Y0110127*
Y0110181*
Y0110235*
Y0110289*
Y0110343*
Y0110397*
Y0110451*
Y0110505*
Y0110559*
Y0110613*
Y0110668*
Y0110722*
Y0110776*
Y011083*
Y0110884*
Y0110938*
Y0110992*
Y0111046*
Y01111*
Y0111154*
Y0111208*
Y0111262*
Y0111316*
Y011137*
Y0111424*
Y0111478*
Y0111532*
Y0111586*
Y0111641*
Y0111695*
Y0111749*
Y0111803*
Y0111857*
Y0111911*
Y0111965*
Y0112019*
Y0112073*
Y0112127*
Y0112181*
Y0112235*
Y0112289*
Y0112343*
Y0112397*
Y0112452*
Y0112505*
Y011256*
Y0112614*
Y0112668*
Y0112722*
Y0112776*
Y011283*
Y0112884*
Y0112938*
Y0112992*
Y0113046*
Y01131*
Y0113154*
Y0113208*
Y0113262*
Y0113317*
Y0113371*
Y0113425*
Y0113479*
Y0113533*
Y0113587*
Y0113641*
Y0113695*
Y0113749*
Y0113803*
Y0113857*
Y0113911*
Y0113965*
Y0114019*
Y0114073*
Y0114127*
Y0114181*
Y0114235*
Y011429*
Y0114344*
Y0114398*
Y0114452*
Y0114506*
Y011456*
Y0114614*
Y0114668*
Y0114722*
Y0114776*
Y011483*
Y0114884*
Y0114938*
Y0114992*
Y0115047*
Y0115101*
Y0115155*
Y0115209*
Y0115263*
Y0115317*
Y0115371*
Y0115425*
Y0115479*
Y0115533*
Y0115587*
Y0115641*
Y0115695*
Y0115749*
Y0115803*
Y0115857*
Y0115911*
Y0115965*
Y011602*
Y0116074*
Y0116128*
Y0116182*
Y0116236*
Y011629*
Y0116344*
Y0116398*
Y0116452*
Y0116506*
Y011656*
Y0116614*
Y0116668*
Y0116722*
Y0116776*
Y0116831*
Y0116885*
Y0116939*
Y0116993*
Y0117047*
Y0117101*
Y0117155*
Y0117209*
Y0117263*
Y0117317*
Y0117371*
Y0117425*
Y0117479*
Y0117533*
Y0117587*
Y0117641*
Y0117695*
X0594241Y0117748*
X0594251Y0117799*
X0594268Y0117849*
X0594291Y0117896*
X059432Y0117939*
X0594355Y0117979*
X0594372Y0117994*
X0594384Y0118004*
X0594409Y0118033*
X0594449Y0118068*
X0594492Y0118097*
X0594539Y011812*
X0594589Y0118137*
X059464Y0118147*
X0594693Y011815*
X0662919*
X0662971Y0118147*
G37*
G36*
X0597178Y0080952D02*
X0597229Y0080942D01*
X0597279Y0080925*
X0597326Y0080902*
X0597396*
X0597448Y0080898*
X0597499Y0080888*
X0597549Y0080871*
X0597596Y0080848*
X0597601Y0080845*
X059761Y0080844*
X0597662Y0080834*
X0597711Y0080817*
X0597758Y0080794*
X0597763Y0080791*
X0597772Y008079*
X0597824Y008078*
X0597873Y0080763*
X0597921Y008074*
X0597951Y0080719*
X0597982Y0080709*
X0598029Y0080686*
X0598059Y0080665*
X059809Y0080655*
X0598137Y0080632*
X059818Y0080603*
X059822Y0080568*
X0598233Y0080553*
X0598252Y0080547*
X0598299Y0080524*
X0598343Y0080494*
X0598382Y008046*
X0598407Y0080431*
X0598436Y0080406*
X0598461Y0080377*
X059849Y0080352*
X0598515Y0080323*
X0598544Y0080298*
X0598569Y0080269*
X0598598Y0080244*
X0598623Y0080215*
X0598652Y008019*
X0598677Y0080161*
X0598696Y0080145*
X0598706Y0080136*
X0598732Y0080107*
X059876Y0080081*
X0598786Y0080053*
X0598814Y0080027*
X0598849Y0079988*
X0598878Y0079944*
X0598901Y0079897*
X0598908Y0079878*
X0598922Y0079865*
X0598957Y0079826*
X0598986Y0079782*
X059901Y0079735*
X059902Y0079705*
X059904Y0079674*
X0599063Y0079627*
X0599074Y0079597*
X0599094Y0079566*
X0599118Y0079519*
X0599128Y0079489*
X0599148Y0079458*
X0599172Y0079411*
X0599189Y0079361*
X0599199Y007931*
Y00793*
X0599202Y0079296*
X0599226Y0079249*
X0599243Y0079199*
X0599253Y0079148*
X0599256Y0079095*
Y007908*
X0599257Y0079079*
X059928Y0079032*
X0599297Y0078983*
X0599307Y0078931*
X059931Y0078879*
Y0078825*
Y0078771*
Y0078717*
Y0078663*
Y0078609*
Y0078555*
Y00785*
Y0078447*
Y0078392*
Y0078338*
Y0078284*
Y007823*
Y0078176*
X0599307Y0078124*
X0599297Y0078072*
X059928Y0078023*
X0599257Y0077976*
X0599256Y0077975*
Y007796*
X0599253Y0077908*
X0599243Y0077856*
X0599226Y0077807*
X0599202Y0077759*
X0599199Y0077755*
Y0077745*
X0599189Y0077694*
X0599172Y0077644*
X0599148Y0077597*
X0599145Y0077593*
Y0077583*
X0599134Y0077532*
X0599118Y0077482*
X0599094Y0077435*
X0599074Y0077404*
X0599069Y0077391*
X0599063Y0077374*
X059904Y0077327*
X0599011Y0077283*
X0598977Y0077244*
X0598962Y0077231*
X0598955Y0077212*
X0598932Y0077165*
X0598903Y0077121*
X0598869Y0077082*
X0598854Y0077069*
X059885Y0077057*
X0598847Y007705*
X0598824Y0077003*
X0598795Y0076959*
X059876Y007692*
X0598732Y0076894*
X0598706Y0076866*
X0598677Y007684*
X0598652Y0076811*
X0598624Y0076786*
X0598598Y0076757*
X0598569Y0076732*
X0598544Y0076703*
X0598515Y0076678*
X059849Y0076649*
X0598451Y0076615*
X0598407Y0076586*
X059836Y0076562*
X0598341Y0076556*
X0598328Y0076541*
X0598288Y0076507*
X0598245Y0076477*
X0598198Y0076454*
X0598179Y0076448*
X0598166Y0076433*
X0598126Y0076398*
X0598083Y0076369*
X0598036Y0076346*
X0598005Y0076336*
X0597974Y0076315*
X0597928Y0076292*
X0597878Y0076275*
X0597826Y0076265*
X0597817Y0076264*
X0597812Y0076261*
X0597765Y0076238*
X0597735Y0076228*
X0597704Y0076207*
X0597657Y0076184*
X0597608Y0076167*
X0597556Y0076157*
X0597504Y0076153*
X0597488*
X0597441Y007613*
X0597391Y0076113*
X059734Y0076103*
X0597288Y0076099*
X0596477*
X0596424Y0076103*
X0596373Y0076113*
X0596323Y007613*
X0596276Y0076153*
X0596271Y0076156*
X0596262Y0076157*
X0596211Y0076167*
X0596161Y0076184*
X0596114Y0076207*
X0596109Y007621*
X05961Y0076211*
X0596048Y0076221*
X0595999Y0076238*
X0595952Y0076261*
X0595947Y0076264*
X0595938Y0076265*
X0595886Y0076275*
X0595837Y0076292*
X059579Y0076315*
X0595746Y0076344*
X0595707Y0076379*
X0595694Y0076394*
X0595675Y00764*
X0595627Y0076423*
X0595597Y0076444*
X0595566Y0076454*
X0595519Y0076477*
X0595476Y0076507*
X0595436Y0076541*
X0595411Y007657*
X0595382Y0076595*
X0595369Y007661*
X059535Y0076617*
X0595303Y007664*
X059526Y0076669*
X059522Y0076703*
X0595195Y0076732*
X0595166Y0076757*
X0595141Y0076786*
X0595112Y0076811*
X0595087Y007684*
X0595058Y0076866*
X0595023Y0076905*
X0594994Y0076949*
X0594971Y0076996*
X0594964Y0077015*
X059495Y0077028*
X0594945Y0077033*
X0594924Y0077057*
X0594896Y0077082*
X0594861Y0077121*
X0594832Y0077165*
X0594809Y0077212*
X0594799Y0077242*
X0594778Y0077273*
X0594755Y007732*
X059475Y0077334*
X0594744Y007735*
X0594724Y0077381*
X0594701Y0077428*
X059469Y0077458*
X059467Y0077489*
X0594647Y0077536*
X0594636Y0077566*
X0594616Y0077597*
X0594593Y0077644*
X0594576Y0077694*
X0594565Y0077745*
Y0077755*
X0594562Y0077759*
X0594538Y0077807*
X0594522Y0077856*
X0594511Y0077908*
X0594508Y007796*
Y0078014*
Y0078029*
Y007803*
X0594484Y0078077*
X0594468Y0078127*
X0594457Y0078178*
X0594454Y007823*
Y0078284*
Y0078338*
Y0078392*
Y0078447*
Y00785*
Y0078555*
Y0078609*
Y0078663*
Y0078717*
Y0078771*
X0594457Y0078823*
X0594468Y0078875*
X0594484Y0078924*
X0594508Y0078971*
Y0078972*
Y0078987*
Y0079041*
X0594511Y0079093*
X0594522Y0079145*
X0594538Y0079195*
X0594562Y0079242*
X0594565Y0079246*
Y0079256*
X0594576Y0079307*
X0594593Y0079357*
X0594616Y0079404*
X0594619Y0079409*
X059462Y0079418*
X059463Y0079469*
X0594647Y0079519*
X059467Y0079566*
X059469Y0079597*
X0594701Y0079627*
X0594724Y0079674*
X0594744Y0079705*
X0594755Y0079735*
X0594778Y0079782*
X0594807Y0079826*
X0594842Y0079865*
X0594856Y0079878*
X0594863Y0079897*
X0594886Y0079944*
X0594915Y0079988*
X059495Y0080027*
X0594979Y0080053*
X0595004Y0080081*
X0595033Y0080107*
X0595058Y0080136*
X0595069Y0080145*
X0595087Y0080161*
X0595112Y008019*
X0595141Y0080215*
X0595166Y0080244*
X0595195Y0080269*
X059522Y0080298*
X0595249Y0080323*
X0595274Y0080352*
X0595303Y0080377*
X0595328Y0080406*
X0595357Y0080431*
X0595382Y008046*
X0595422Y0080494*
X0595465Y0080524*
X0595512Y0080547*
X0595543Y0080557*
X0595573Y0080578*
X059562Y0080601*
X059564Y0080607*
X0595652Y0080622*
X0595692Y0080657*
X0595736Y0080686*
X0595783Y0080709*
X0595813Y0080719*
X0595844Y008074*
X0595891Y0080763*
X059594Y008078*
X0595992Y008079*
X0596001Y0080791*
X0596006Y0080794*
X0596053Y0080817*
X0596103Y0080834*
X0596154Y0080844*
X0596163Y0080845*
X0596168Y0080848*
X0596215Y0080871*
X0596265Y0080888*
X0596316Y0080898*
X0596369Y0080902*
X0596438*
X0596485Y0080925*
X0596535Y0080942*
X0596587Y0080952*
X0596639Y0080956*
X0597125*
X0597178Y0080952*
G37*
G36*
X0597394Y00736D02*
X0597445Y007359D01*
X0597495Y0073573*
X0597542Y007355*
X0597543Y0073549*
X0597558*
X059761Y0073546*
X0597662Y0073536*
X0597711Y0073519*
X0597758Y0073496*
X0597789Y0073475*
X0597819Y0073465*
X0597866Y0073441*
X0597897Y0073421*
X0597928Y0073411*
X0597974Y0073387*
X0598005Y0073367*
X0598036Y0073357*
X0598083Y0073333*
X0598113Y0073313*
X0598144Y0073303*
X0598191Y0073279*
X0598234Y007325*
X0598274Y0073216*
X0598287Y0073201*
X0598306Y0073194*
X0598353Y0073171*
X0598397Y0073142*
X0598436Y0073107*
X0598461Y0073079*
X059849Y0073053*
X0598515Y0073025*
X0598544Y0072999*
X0598569Y0072971*
X0598598Y0072945*
X0598623Y0072917*
X0598652Y0072891*
X0598677Y0072862*
X0598706Y0072837*
X0598732Y0072808*
X059876Y0072783*
X0598786Y0072754*
X0598814Y0072729*
X0598849Y007269*
X0598878Y0072646*
X0598901Y0072599*
X0598906Y0072585*
X0598908Y007258*
X0598922Y0072567*
X0598957Y0072527*
X0598986Y0072484*
X059901Y0072437*
X059902Y0072407*
X059904Y0072376*
X0599063Y0072329*
X0599074Y0072298*
X0599094Y0072268*
X0599118Y0072221*
X0599128Y007219*
X0599138Y0072175*
X0599148Y0072159*
X0599172Y0072113*
X0599189Y0072063*
X0599199Y0072011*
Y0072002*
X0599202Y0071997*
X0599226Y007195*
X0599243Y0071901*
X0599253Y0071849*
X0599256Y0071797*
Y0071743*
Y0071728*
X0599257Y0071727*
X059928Y007168*
X0599297Y007163*
X0599307Y0071579*
X059931Y0071526*
Y0071473*
Y0071418*
Y0071364*
Y007131*
Y0071256*
Y0071202*
Y0071148*
Y0071094*
Y007104*
Y0070986*
Y0070932*
Y0070878*
X0599307Y0070825*
X0599297Y0070774*
X059928Y0070724*
X0599257Y0070677*
X0599256*
Y0070662*
Y0070608*
X0599253Y0070555*
X0599243Y0070504*
X0599226Y0070454*
X0599202Y0070407*
X0599199Y0070402*
Y0070393*
X0599189Y0070342*
X0599172Y0070292*
X0599148Y0070245*
X0599128Y0070214*
X0599118Y0070184*
X0599094Y0070137*
X0599074Y0070106*
X0599066Y0070083*
X0599063Y0070076*
X059904Y0070029*
X059902Y0069998*
X059901Y0069968*
X0598986Y006992*
X0598957Y0069877*
X0598922Y0069837*
X0598908Y0069825*
X0598901Y0069805*
X0598878Y0069758*
X0598849Y0069715*
X0598814Y0069675*
X0598786Y006965*
X059876Y0069621*
X0598732Y0069596*
X0598706Y0069567*
X0598677Y0069542*
X0598652Y0069513*
X0598624Y0069488*
X0598598Y0069459*
X0598569Y0069434*
X0598544Y0069405*
X0598515Y006938*
X059849Y0069351*
X0598461Y0069326*
X0598436Y0069297*
X0598397Y0069262*
X0598353Y0069233*
X0598306Y006921*
X0598287Y0069203*
X0598274Y0069189*
X0598234Y0069154*
X0598191Y0069125*
X0598144Y0069102*
X0598113Y0069092*
X0598083Y0069071*
X0598036Y0069048*
X0598005Y0069037*
X0597974Y0069017*
X0597928Y0068994*
X0597897Y0068983*
X0597866Y0068963*
X0597819Y006894*
X059777Y0068923*
X0597718Y0068913*
X0597709Y0068912*
X0597704Y0068909*
X0597657Y0068886*
X0597608Y0068869*
X0597556Y0068858*
X0597547*
X0597542Y0068855*
X0597495Y0068831*
X0597445Y0068815*
X0597394Y0068804*
X0597342Y0068801*
X0596423*
X059637Y0068804*
X0596319Y0068815*
X0596269Y0068831*
X0596222Y0068855*
X0596217Y0068858*
X0596208*
X0596157Y0068869*
X0596107Y0068886*
X059606Y0068909*
X0596055Y0068912*
X0596046Y0068913*
X0595994Y0068923*
X0595945Y006894*
X0595898Y0068963*
X0595867Y0068983*
X0595837Y0068994*
X059579Y0069017*
X0595759Y0069037*
X0595728Y0069048*
X0595681Y0069071*
X0595651Y0069092*
X059562Y0069102*
X0595573Y0069125*
X059553Y0069154*
X059549Y0069189*
X0595477Y0069203*
X0595465Y0069217*
X0595436Y0069243*
X0595423Y0069257*
X0595404Y0069264*
X0595357Y0069287*
X0595314Y0069316*
X0595274Y0069351*
X0595249Y006938*
X059522Y0069405*
X0595195Y0069434*
X0595166Y0069459*
X0595162Y0069463*
X0595141Y0069488*
X0595112Y0069513*
X0595087Y0069542*
X0595058Y0069567*
X0595033Y0069596*
X0595004Y0069621*
X0594969Y0069661*
X059494Y0069704*
X0594917Y0069751*
X059491Y0069771*
X0594896Y0069783*
X0594861Y0069823*
X0594832Y0069866*
X0594809Y0069914*
X0594799Y0069944*
X0594778Y0069975*
X0594755Y0070022*
X0594744Y0070052*
X0594724Y0070083*
X0594701Y007013*
X059469Y007016*
X059467Y0070191*
X0594647Y0070238*
X0594636Y0070268*
X0594616Y0070299*
X0594593Y0070346*
X0594576Y0070396*
X0594565Y0070447*
Y0070456*
X0594562Y0070461*
X0594538Y0070508*
X0594522Y0070558*
X0594511Y0070609*
X0594508Y0070662*
Y0070716*
Y0070731*
X0594484Y0070779*
X0594468Y0070828*
X0594457Y007088*
X0594454Y0070932*
Y0070986*
Y007104*
Y0071094*
Y0071148*
Y0071202*
Y0071256*
Y007131*
Y0071364*
Y0071418*
Y0071473*
X0594457Y0071525*
X0594468Y0071576*
X0594484Y0071626*
X0594508Y0071673*
Y0071689*
Y0071743*
X0594511Y0071795*
X0594522Y0071847*
X0594538Y0071896*
X0594562Y0071943*
X0594565Y0071948*
Y0071957*
X0594576Y0072009*
X0594593Y0072058*
X0594616Y0072105*
X0594636Y0072136*
X0594647Y0072167*
X059467Y0072214*
X059469Y0072244*
X0594701Y0072275*
X0594724Y0072322*
X0594744Y0072352*
X0594755Y0072383*
X0594778Y007243*
X0594799Y0072461*
X0594809Y0072491*
X0594832Y0072538*
X0594861Y0072581*
X0594896Y0072621*
X059491Y0072634*
X0594917Y0072653*
X059494Y00727*
X0594969Y0072744*
X0595004Y0072783*
X0595033Y0072808*
X0595058Y0072837*
X0595087Y0072862*
X0595112Y0072891*
X0595141Y0072917*
X0595166Y0072945*
X0595195Y0072971*
X059522Y0072999*
X0595249Y0073025*
X0595274Y0073053*
X0595303Y0073079*
X0595328Y0073107*
X0595368Y0073142*
X0595411Y0073171*
X0595458Y0073194*
X0595477Y0073201*
X059549Y0073216*
X059553Y007325*
X0595573Y0073279*
X059562Y0073303*
X0595651Y0073313*
X0595681Y0073333*
X0595728Y0073357*
X0595759Y0073367*
X059579Y0073387*
X0595837Y0073411*
X0595867Y0073421*
X0595898Y0073441*
X0595945Y0073465*
X0595994Y0073482*
X0596046Y0073492*
X0596055*
X059606Y0073496*
X0596107Y0073519*
X0596157Y0073536*
X0596208Y0073546*
X0596217*
X0596222Y007355*
X0596269Y0073573*
X0596319Y007359*
X059637Y00736*
X0596423Y0073603*
X0597342*
X0597394Y00736*
G37*
G36*
X057874Y0067913D02*
X0378937D01*
Y0267717*
X057874*
Y0067913*
G37*
G36*
X0589501Y0118147D02*
X0589552Y0118137D01*
X0589602Y011812*
X0589649Y0118097*
Y0118096*
X0589989*
X0590041Y0118093*
X0590093Y0118083*
X0590143Y0118066*
X059019Y0118043*
Y0118042*
X0590205*
X0590258Y0118039*
X0590309Y0118029*
X0590359Y0118012*
X0590406Y0117989*
Y0117988*
X0590422*
X0590474Y0117985*
X0590525Y0117975*
X0590575Y0117958*
X0590622Y0117935*
X0590653Y0117914*
X0590683Y0117904*
X059073Y011788*
X0590735Y0117877*
X0590744*
X0590796Y0117867*
X0590845Y011785*
X0590892Y0117826*
X0590923Y0117806*
X0590953Y0117796*
X0591001Y0117772*
X0591031Y0117752*
X0591062Y0117742*
X0591109Y0117718*
X059114Y0117698*
X059117Y0117687*
X0591217Y0117664*
X0591248Y0117644*
X0591278Y0117633*
X0591325Y011761*
X0591368Y0117581*
X0591408Y0117546*
X0591421Y0117532*
X059144Y0117525*
X0591487Y0117502*
X0591531Y0117473*
X059157Y0117438*
X0591595Y011741*
X0591624Y0117384*
X0591637Y011737*
X0591656Y0117363*
X0591703Y011734*
X0591747Y0117311*
X0591786Y0117276*
X0591812Y0117247*
X059184Y0117222*
X0591866Y0117193*
X0591894Y0117168*
X059192Y0117139*
X0591949Y0117114*
X0591974Y0117085*
X0592003Y011706*
X0592028Y0117031*
X0592057Y0117006*
X0592082Y0116977*
X0592111Y0116952*
X0592136Y0116923*
X059215Y0116911*
X0592165Y0116898*
X059219Y0116869*
X0592219Y0116844*
X0592253Y0116804*
X0592283Y0116761*
X0592306Y0116714*
X0592312Y0116694*
X0592327Y0116682*
X0592352Y0116653*
X0592381Y0116627*
X0592416Y0116588*
X0592445Y0116544*
X0592468Y0116497*
X0592475Y0116478*
X0592489Y0116465*
X0592524Y0116426*
X0592553Y0116382*
X0592576Y0116335*
X0592586Y0116305*
X0592607Y0116274*
X059263Y0116227*
X059264Y0116197*
X0592661Y0116166*
X0592684Y0116119*
X0592695Y0116089*
X0592715Y0116058*
X0592738Y0116011*
X0592746Y0115988*
X0592748Y0115981*
X0592769Y011595*
X0592792Y0115903*
X0592809Y0115853*
X0592819Y0115802*
X059282Y0115792*
X0592823Y0115787*
X0592846Y0115741*
X0592857Y011571*
X0592877Y0115679*
X05929Y0115632*
X0592917Y0115583*
X0592928Y0115531*
X0592931Y0115479*
Y0115464*
Y0115463*
X0592954Y0115416*
X0592971Y0115366*
X0592982Y0115315*
X0592985Y0115263*
Y0115209*
Y0115193*
X0593009Y0115146*
X0593025Y0115096*
X0593036Y0115045*
X0593039Y0114992*
Y0114938*
Y0114884*
Y011483*
Y0114776*
Y0114722*
Y0114668*
Y0114614*
Y011456*
Y0114506*
Y0114452*
Y0114398*
Y0114344*
Y011429*
Y0114235*
Y0114181*
Y0114127*
Y0114073*
Y0114019*
Y0113965*
Y0113911*
Y0113857*
Y0113803*
Y0113749*
Y0113695*
Y0113641*
Y0113587*
Y0113533*
Y0113479*
Y0113425*
Y0113371*
Y0113317*
Y0113262*
Y0113208*
Y0113154*
Y01131*
Y0113046*
Y0112992*
Y0112938*
Y0112884*
Y011283*
Y0112776*
Y0112722*
Y0112668*
Y0112614*
Y011256*
Y0112505*
Y0112452*
Y0112397*
Y0112343*
Y0112289*
Y0112235*
Y0112181*
Y0112127*
Y0112073*
Y0112019*
Y0111965*
Y0111911*
Y0111857*
Y0111803*
Y0111749*
Y0111695*
Y0111641*
Y0111586*
Y0111532*
Y0111478*
Y0111424*
Y011137*
Y0111316*
Y0111262*
Y0111208*
Y0111154*
Y01111*
Y0111046*
Y0110992*
Y0110938*
Y0110884*
Y011083*
Y0110776*
Y0110722*
Y0110668*
Y0110613*
Y0110559*
Y0110505*
Y0110451*
Y0110397*
Y0110343*
Y0110289*
Y0110235*
Y0110181*
Y0110127*
Y0110073*
Y0110019*
Y0109965*
Y0109911*
Y0109856*
Y0109802*
Y0109748*
Y0109694*
Y010964*
Y0109586*
Y0109532*
Y0109478*
Y0109424*
Y010937*
Y0109316*
Y0109262*
Y0109208*
Y0109154*
Y01091*
Y0109046*
Y0108992*
Y0108938*
Y0108883*
Y0108829*
Y0108775*
Y0108721*
Y0108667*
Y0108613*
Y0108559*
Y0108505*
Y0108451*
Y0108397*
Y0108343*
Y0108289*
Y0108235*
Y0108181*
Y0108126*
Y0108072*
Y0108018*
Y0107964*
Y010791*
Y0107856*
Y0107802*
Y0107748*
Y0107694*
Y010764*
Y0107586*
Y0107532*
Y0107478*
Y0107424*
Y010737*
Y0107316*
Y0107262*
Y0107208*
Y0107153*
Y0107099*
Y0107045*
Y0106991*
Y0106937*
Y0106883*
Y0106829*
Y0106775*
Y0106721*
Y0106667*
Y0106613*
Y0106559*
Y0106505*
Y0106451*
Y0106397*
Y0106342*
Y0106288*
Y0106234*
Y010618*
Y0106126*
Y0106072*
Y0106018*
Y0105964*
Y010591*
Y0105856*
Y0105802*
Y0105748*
Y0105694*
Y010564*
Y0105586*
Y0105532*
Y0105477*
Y0105423*
Y0105369*
Y0105315*
Y0105261*
Y0105207*
Y0105153*
Y0105099*
Y0105045*
Y0104991*
Y0104937*
Y0104883*
Y0104829*
Y0104775*
Y0104721*
Y0104667*
Y0104613*
Y0104558*
Y0104504*
Y010445*
Y0104396*
Y0104342*
Y0104288*
Y0104234*
Y010418*
Y0104126*
Y0104072*
Y0104018*
Y0103964*
Y010391*
Y0103856*
Y0103802*
Y0103747*
Y0103693*
Y0103639*
Y0103585*
Y0103531*
Y0103477*
Y0103423*
Y0103369*
Y0103315*
Y0103261*
Y0103207*
Y0103153*
Y0103099*
Y0103045*
Y0102991*
Y0102937*
Y0102883*
Y0102828*
Y0102774*
Y010272*
Y0102666*
Y0102612*
Y0102558*
Y0102504*
Y010245*
Y0102396*
Y0102342*
Y0102288*
Y0102234*
Y010218*
Y0102126*
Y0102072*
Y0102017*
Y0101963*
Y0101909*
Y0101855*
Y0101801*
Y0101747*
Y0101693*
Y0101639*
Y0101585*
Y0101531*
Y0101477*
Y0101423*
Y0101369*
Y0101315*
Y0101261*
Y0101207*
Y0101153*
Y0101099*
Y0101044*
Y010099*
Y0100936*
Y0100882*
Y0100828*
Y0100774*
Y010072*
Y0100666*
Y0100612*
Y0100558*
Y0100504*
Y010045*
Y0100396*
Y0100342*
Y0100287*
Y0100233*
Y0100179*
Y0100125*
Y0100071*
Y0100017*
Y0099963*
Y0099909*
Y0099855*
Y0099801*
Y0099747*
Y0099693*
Y0099639*
Y0099585*
Y0099531*
Y0099477*
Y0099423*
Y0099369*
Y0099314*
Y009926*
Y0099206*
Y0099152*
Y0099098*
Y0099044*
Y009899*
Y0098936*
Y0098882*
Y0098828*
Y0098774*
Y009872*
Y0098666*
Y0098612*
Y0098558*
Y0098504*
Y0098449*
Y0098395*
Y0098341*
Y0098287*
Y0098233*
Y0098179*
Y0098125*
Y0098071*
Y0098017*
Y0097963*
Y0097909*
Y0097855*
Y0097801*
Y0097747*
Y0097693*
Y0097638*
Y0097584*
Y009753*
Y0097476*
Y0097422*
Y0097368*
Y0097314*
Y009726*
Y0097206*
Y0097152*
Y0097098*
Y0097044*
Y009699*
Y0096936*
Y0096882*
Y0096828*
Y0096773*
Y0096719*
Y0096665*
Y0096611*
Y0096557*
Y0096503*
Y0096449*
Y0096395*
Y0096341*
Y0096287*
Y0096233*
Y0096179*
Y0096125*
Y0096071*
Y0096017*
Y0095963*
Y0095908*
Y0095854*
Y00958*
Y0095746*
Y0095692*
Y0095638*
Y0095584*
Y009553*
Y0095476*
Y0095422*
Y0095368*
Y0095314*
Y009526*
Y0095206*
Y0095152*
Y0095098*
Y0095043*
Y009499*
Y0094935*
Y0094881*
Y0094827*
Y0094773*
Y0094719*
Y0094665*
Y0094611*
Y0094557*
Y0094503*
Y0094449*
Y0094395*
Y0094341*
Y0094287*
Y0094233*
Y0094178*
Y0094125*
Y009407*
Y0094016*
Y0093962*
Y0093908*
Y0093854*
Y00938*
Y0093746*
Y0093692*
Y0093638*
Y0093584*
Y009353*
Y0093476*
Y0093422*
Y0093368*
Y0093313*
Y009326*
Y0093205*
Y0093151*
Y0093097*
Y0093043*
Y0092989*
Y0092935*
Y0092881*
Y0092827*
Y0092773*
Y0092719*
Y0092665*
Y0092611*
Y0092557*
Y0092503*
Y0092449*
Y0092395*
Y009234*
Y0092286*
Y0092232*
Y0092178*
Y0092124*
Y009207*
Y0092016*
Y0091962*
Y0091908*
Y0091854*
Y00918*
Y0091746*
Y0091692*
Y0091638*
Y0091584*
Y009153*
Y0091475*
Y0091421*
Y0091367*
Y0091313*
Y0091259*
Y0091205*
Y0091151*
Y0091097*
Y0091043*
Y0090989*
Y0090935*
Y0090881*
Y0090827*
Y0090773*
Y0090719*
Y0090664*
Y009061*
Y0090556*
Y0090502*
Y0090448*
Y0090394*
Y009034*
Y0090286*
Y0090232*
Y0090178*
Y0090124*
Y009007*
Y0090016*
Y0089962*
Y0089908*
Y0089854*
Y0089799*
Y0089745*
Y0089691*
Y0089637*
Y0089583*
Y0089529*
Y0089475*
Y0089421*
Y0089367*
Y0089313*
Y0089259*
Y0089205*
Y0089151*
Y0089097*
Y0089043*
Y0088989*
Y0088934*
Y008888*
Y0088826*
Y0088772*
Y0088718*
Y0088664*
Y008861*
Y0088556*
Y0088502*
Y0088448*
Y0088394*
Y008834*
Y0088286*
Y0088232*
Y0088178*
Y0088124*
Y0088069*
Y0088016*
Y0087961*
Y0087907*
Y0087853*
Y0087799*
Y0087745*
Y0087691*
Y0087637*
Y0087583*
Y0087529*
Y0087475*
Y0087421*
Y0087367*
Y0087313*
Y0087259*
Y0087204*
Y0087151*
Y0087096*
Y0087042*
Y0086988*
Y0086934*
Y008688*
Y0086826*
Y0086772*
Y0086718*
Y0086664*
Y008661*
Y0086556*
Y0086502*
Y0086448*
Y0086394*
Y0086339*
Y0086286*
Y0086231*
Y0086177*
Y0086123*
Y0086069*
Y0086015*
Y0085961*
Y0085907*
Y0085853*
Y0085799*
Y0085745*
Y0085691*
Y0085637*
Y0085583*
Y0085529*
Y0085474*
Y0085421*
Y0085366*
Y0085312*
Y0085258*
Y0085204*
Y008515*
Y0085096*
Y0085042*
Y0084988*
Y0084934*
Y008488*
Y0084826*
Y0084772*
Y0084718*
Y0084664*
Y008461*
Y0084556*
Y0084501*
Y0084447*
Y0084393*
Y0084339*
Y0084285*
Y0084231*
Y0084177*
Y0084123*
Y0084069*
Y0084015*
Y0083961*
Y0083907*
Y0083853*
Y0083799*
Y0083745*
Y0083691*
Y0083636*
Y0083582*
Y0083528*
Y0083474*
Y008342*
Y0083366*
Y0083312*
Y0083258*
Y0083204*
Y008315*
Y0083096*
Y0083042*
Y0082988*
Y0082934*
Y008288*
Y0082825*
Y0082771*
Y0082717*
Y0082663*
Y0082609*
Y0082555*
Y0082501*
Y0082447*
Y0082393*
Y0082339*
Y0082285*
Y0082231*
Y0082177*
Y0082123*
Y0082069*
Y0082015*
Y008196*
Y0081906*
Y0081852*
Y0081798*
Y0081744*
Y008169*
Y0081636*
Y0081582*
Y0081528*
Y0081474*
Y008142*
Y0081366*
Y0081312*
Y0081258*
Y0081204*
Y008115*
Y0081095*
Y0081042*
Y0080987*
Y0080933*
Y0080879*
Y0080825*
Y0080771*
Y0080717*
Y0080663*
Y0080609*
Y0080555*
Y0080501*
Y0080447*
Y0080393*
Y0080339*
Y0080285*
Y008023*
Y0080177*
Y0080122*
Y0080068*
Y0080014*
Y007996*
Y0079906*
Y0079852*
Y0079798*
Y0079744*
Y007969*
Y0079636*
Y0079582*
Y0079528*
Y0079474*
Y007942*
Y0079365*
Y0079312*
Y0079257*
Y0079203*
Y0079149*
Y0079095*
Y0079041*
Y0078987*
Y0078933*
Y0078879*
Y0078825*
Y0078771*
Y0078717*
Y0078663*
Y0078609*
Y0078555*
Y00785*
Y0078447*
Y0078392*
Y0078338*
Y0078284*
Y007823*
Y0078176*
Y0078122*
Y0078068*
Y0078014*
Y007796*
Y0077906*
Y0077852*
Y0077798*
Y0077744*
Y007769*
Y0077636*
Y0077582*
Y0077527*
Y0077473*
Y0077419*
Y0077365*
Y0077311*
Y0077257*
Y0077203*
Y0077149*
Y0077095*
Y0077041*
Y0076987*
Y0076933*
Y0076879*
Y0076825*
Y0076771*
Y0076717*
Y0076662*
Y0076608*
Y0076554*
Y00765*
Y0076446*
Y0076392*
Y0076338*
Y0076284*
Y007623*
Y0076176*
Y0076122*
Y0076068*
Y0076014*
Y007596*
Y0075906*
Y0075852*
Y0075797*
Y0075743*
Y0075689*
Y0075635*
Y0075581*
Y0075527*
Y0075473*
Y0075419*
Y0075365*
Y0075311*
Y0075257*
Y0075203*
Y0075149*
Y0075095*
Y0075041*
Y0074986*
Y0074932*
Y0074878*
Y0074824*
Y007477*
Y0074716*
Y0074662*
Y0074608*
Y0074554*
Y00745*
Y0074446*
Y0074392*
Y0074338*
Y0074284*
Y007423*
Y0074176*
Y0074121*
Y0074067*
Y0074013*
Y0073959*
Y0073905*
Y0073851*
Y0073797*
Y0073743*
Y0073689*
Y0073635*
Y0073581*
Y0073527*
Y0073473*
Y0073419*
Y0073365*
Y0073311*
Y0073256*
Y0073203*
Y0073148*
Y0073094*
Y007304*
Y0072986*
Y0072932*
Y0072878*
Y0072824*
Y007277*
Y0072716*
Y0072662*
Y0072608*
Y0072554*
Y00725*
Y0072446*
Y0072391*
Y0072338*
Y0072283*
Y0072229*
Y0072175*
Y0072121*
Y0072067*
Y0072013*
Y0071959*
Y0071905*
Y0071851*
Y0071797*
Y0071743*
Y0071689*
Y0071635*
Y0071581*
Y0071526*
Y0071473*
Y0071418*
Y0071364*
Y007131*
Y0071256*
Y0071202*
Y0071148*
Y0071094*
Y007104*
Y0070986*
Y0070932*
Y0070878*
Y0070824*
Y007077*
Y0070716*
Y0070662*
Y0070608*
Y0070553*
Y0070499*
Y0070445*
Y0070391*
Y0070337*
Y0070283*
Y0070229*
Y0070175*
Y0070121*
Y0070067*
Y0070013*
Y0069959*
Y0069905*
Y0069851*
Y0069797*
Y0069743*
Y0069688*
Y0069634*
Y006958*
Y0069526*
Y0069472*
Y0069418*
Y0069364*
Y006931*
Y0069256*
Y0069202*
Y0069148*
Y0069094*
Y006904*
Y0068986*
Y0068932*
Y0068878*
Y0068823*
Y0068769*
Y0068715*
Y0068661*
Y0068607*
Y0068553*
Y0068499*
Y0068445*
Y0068391*
Y0068337*
Y0068283*
Y0068229*
Y0068175*
Y0068121*
Y0068067*
Y0068012*
Y0067958*
Y0067904*
Y006785*
Y0067796*
Y0067742*
Y0067688*
Y0067634*
Y006758*
Y0067526*
Y0067472*
Y0067418*
Y0067364*
Y006731*
Y0067256*
Y0067202*
Y0067147*
Y0067093*
Y0067039*
Y0066985*
Y0066931*
Y0066877*
Y0066823*
Y0066769*
Y0066715*
Y0066661*
Y0066607*
Y0066553*
Y0066499*
Y0066445*
Y0066391*
Y0066337*
Y0066282*
Y0066228*
Y0066174*
Y006612*
Y0066066*
Y0066012*
Y0065958*
Y0065904*
Y006585*
Y0065796*
Y0065742*
Y0065688*
Y0065634*
Y006558*
Y0065526*
Y0065472*
Y0065417*
Y0065364*
Y0065309*
Y0065255*
Y0065201*
Y0065147*
Y0065093*
Y0065039*
Y0064985*
Y0064931*
Y0064877*
Y0064823*
Y0064769*
Y0064715*
Y0064661*
Y0064607*
Y0064552*
Y0064499*
Y0064444*
Y006439*
Y0064336*
Y0064282*
Y0064228*
Y0064174*
Y006412*
Y0064066*
Y0064012*
Y0063958*
Y0063904*
Y006385*
Y0063796*
Y0063742*
Y0063688*
Y0063634*
Y0063579*
Y0063525*
Y0063471*
Y0063417*
Y0063363*
Y0063309*
Y0063255*
Y0063201*
Y0063147*
Y0063093*
Y0063039*
Y0062985*
Y0062931*
Y0062877*
Y0062823*
Y0062769*
Y0062714*
Y006266*
Y0062606*
Y0062552*
Y0062498*
Y0062444*
Y006239*
Y0062336*
Y0062282*
Y0062228*
Y0062174*
Y006212*
Y0062066*
Y0062012*
Y0061958*
Y0061904*
Y0061849*
Y0061795*
Y0061741*
Y0061687*
Y0061633*
Y0061579*
Y0061525*
Y0061471*
Y0061417*
Y0061363*
Y0061309*
Y0061255*
Y0061201*
Y0061147*
Y0061093*
Y0061039*
Y0060984*
Y006093*
Y0060876*
Y0060822*
Y0060768*
Y0060714*
Y006066*
Y0060606*
Y0060552*
Y0060498*
Y0060444*
Y006039*
Y0060336*
Y0060282*
Y0060228*
Y0060173*
Y0060119*
Y0060065*
Y0060011*
Y0059957*
Y0059903*
Y0059849*
Y0059795*
Y0059741*
Y0059687*
Y0059633*
Y0059579*
Y0059525*
Y0059471*
Y0059417*
Y0059363*
Y0059308*
Y0059254*
Y00592*
Y0059146*
Y0059092*
Y0059038*
Y0058984*
Y005893*
Y0058876*
Y0058822*
Y0058768*
Y0058714*
Y005866*
Y0058606*
Y0058552*
Y0058498*
Y0058443*
Y005839*
Y0058335*
Y0058281*
Y0058227*
Y0058173*
Y0058119*
Y0058065*
Y0058011*
Y0057957*
Y0057903*
Y0057849*
Y0057795*
Y0057741*
Y0057687*
Y0057633*
Y0057578*
Y0057525*
Y005747*
Y0057416*
Y0057362*
Y0057308*
Y0057254*
Y00572*
Y0057146*
Y0057092*
Y0057038*
Y0056984*
Y005693*
Y0056876*
Y0056822*
Y0056768*
Y0056714*
Y005666*
Y0056605*
Y0056551*
Y0056497*
Y0056443*
Y0056389*
Y0056335*
Y0056281*
Y0056227*
Y0056173*
Y0056119*
Y0056065*
Y0056011*
Y0055957*
X0593036Y0055904*
X0593025Y0055853*
X0593009Y0055803*
X0592985Y0055756*
X0592956Y0055713*
X0592922Y0055673*
X0592882Y0055639*
X0592839Y005561*
X0592792Y0055586*
X0592742Y0055569*
X0592691Y0055559*
X0592638Y0055556*
X0590638*
X0590586Y0055559*
X0590534Y0055569*
X0590485Y0055586*
X0590438Y005561*
X0590394Y0055639*
X0590354Y0055673*
X059032Y0055713*
X0590291Y0055756*
X0590268Y0055803*
X0590251Y0055853*
X059024Y0055904*
X0590237Y0055957*
Y0056011*
Y0056065*
Y0056119*
Y0056173*
Y0056227*
Y0056281*
Y0056335*
Y0056389*
Y0056443*
Y0056497*
Y0056551*
Y0056605*
Y005666*
Y0056714*
Y0056768*
Y0056822*
Y0056876*
Y005693*
Y0056984*
Y0057038*
Y0057092*
Y0057146*
Y00572*
Y0057254*
Y0057308*
Y0057362*
Y0057416*
Y005747*
Y0057525*
Y0057578*
Y0057633*
Y0057687*
Y0057741*
Y0057795*
Y0057849*
Y0057903*
Y0057957*
Y0058011*
Y0058065*
Y0058119*
Y0058173*
Y0058227*
Y0058281*
Y0058335*
Y005839*
Y0058443*
Y0058498*
Y0058552*
Y0058606*
Y005866*
Y0058714*
Y0058768*
Y0058822*
Y0058876*
Y005893*
Y0058984*
Y0059038*
Y0059092*
Y0059146*
Y00592*
Y0059254*
Y0059308*
Y0059363*
Y0059417*
Y0059471*
Y0059525*
Y0059579*
Y0059633*
Y0059687*
Y0059741*
Y0059795*
Y0059849*
Y0059903*
Y0059957*
Y0060011*
Y0060065*
Y0060119*
Y0060173*
Y0060228*
Y0060282*
Y0060336*
Y006039*
Y0060444*
Y0060498*
Y0060552*
Y0060606*
Y006066*
Y0060714*
Y0060768*
Y0060822*
Y0060876*
Y006093*
Y0060984*
Y0061039*
Y0061093*
Y0061147*
Y0061201*
Y0061255*
Y0061309*
Y0061363*
Y0061417*
Y0061471*
Y0061525*
Y0061579*
Y0061633*
Y0061687*
Y0061741*
Y0061795*
Y0061849*
Y0061904*
Y0061958*
Y0062012*
Y0062066*
Y006212*
Y0062174*
Y0062228*
Y0062282*
Y0062336*
Y006239*
Y0062444*
Y0062498*
Y0062552*
Y0062606*
Y006266*
Y0062714*
Y0062769*
Y0062823*
Y0062877*
Y0062931*
Y0062985*
Y0063039*
Y0063093*
Y0063147*
Y0063201*
Y0063255*
Y0063309*
Y0063363*
Y0063417*
Y0063471*
Y0063525*
Y0063579*
Y0063634*
Y0063688*
Y0063742*
Y0063796*
Y006385*
Y0063904*
Y0063958*
Y0064012*
Y0064066*
Y006412*
Y0064174*
Y0064228*
Y0064282*
Y0064336*
Y006439*
Y0064444*
Y0064499*
Y0064552*
Y0064607*
Y0064661*
Y0064715*
Y0064769*
Y0064823*
Y0064877*
Y0064931*
Y0064985*
Y0065039*
Y0065093*
Y0065147*
Y0065201*
Y0065255*
Y0065309*
Y0065364*
Y0065417*
Y0065472*
Y0065526*
Y006558*
Y0065634*
Y0065688*
Y0065742*
Y0065796*
Y006585*
Y0065904*
Y0065958*
Y0066012*
Y0066066*
Y006612*
Y0066174*
Y0066228*
Y0066282*
Y0066337*
Y0066391*
Y0066445*
Y0066499*
Y0066553*
Y0066607*
Y0066661*
Y0066715*
Y0066769*
Y0066823*
Y0066877*
Y0066931*
Y0066985*
Y0067039*
Y0067093*
Y0067147*
Y0067202*
Y0067256*
Y006731*
Y0067364*
Y0067418*
Y0067472*
Y0067526*
Y006758*
Y0067634*
Y0067688*
Y0067742*
Y0067796*
Y006785*
Y0067904*
Y0067958*
Y0068012*
Y0068067*
Y0068121*
Y0068175*
Y0068229*
Y0068283*
Y0068337*
Y0068391*
Y0068445*
Y0068499*
Y0068553*
Y0068607*
Y0068661*
Y0068715*
Y0068769*
Y0068823*
Y0068878*
Y0068932*
Y0068986*
Y006904*
Y0069094*
Y0069148*
Y0069202*
Y0069256*
Y006931*
Y0069364*
Y0069418*
Y0069472*
Y0069526*
Y006958*
Y0069634*
Y0069688*
Y0069743*
Y0069797*
Y0069851*
Y0069905*
Y0069959*
Y0070013*
Y0070067*
Y0070121*
Y0070175*
Y0070229*
Y0070283*
Y0070337*
Y0070391*
Y0070445*
Y0070499*
Y0070553*
Y0070608*
Y0070662*
Y0070716*
Y007077*
Y0070824*
Y0070878*
Y0070932*
Y0070986*
Y007104*
Y0071094*
Y0071148*
Y0071202*
Y0071256*
Y007131*
Y0071364*
Y0071418*
Y0071473*
Y0071526*
Y0071581*
Y0071635*
Y0071689*
Y0071743*
Y0071797*
Y0071851*
Y0071905*
Y0071959*
Y0072013*
Y0072067*
Y0072121*
Y0072175*
Y0072229*
Y0072283*
Y0072338*
Y0072391*
Y0072446*
Y00725*
Y0072554*
Y0072608*
Y0072662*
Y0072716*
Y007277*
Y0072824*
Y0072878*
Y0072932*
Y0072986*
Y007304*
Y0073094*
Y0073148*
Y0073203*
Y0073256*
Y0073311*
Y0073365*
Y0073419*
Y0073473*
Y0073527*
Y0073581*
Y0073635*
Y0073689*
Y0073743*
Y0073797*
Y0073851*
Y0073905*
Y0073959*
Y0074013*
Y0074067*
Y0074121*
Y0074176*
Y007423*
Y0074284*
Y0074338*
Y0074392*
Y0074446*
Y00745*
Y0074554*
Y0074608*
Y0074662*
Y0074716*
Y007477*
Y0074824*
Y0074878*
Y0074932*
Y0074986*
Y0075041*
Y0075095*
Y0075149*
Y0075203*
Y0075257*
Y0075311*
Y0075365*
Y0075419*
Y0075473*
Y0075527*
Y0075581*
Y0075635*
Y0075689*
Y0075743*
Y0075797*
Y0075852*
Y0075906*
Y007596*
Y0076014*
Y0076068*
Y0076122*
Y0076176*
Y007623*
Y0076284*
Y0076338*
Y0076392*
Y0076446*
Y00765*
Y0076554*
Y0076608*
Y0076662*
Y0076717*
Y0076771*
Y0076825*
Y0076879*
Y0076933*
Y0076987*
Y0077041*
Y0077095*
Y0077149*
Y0077203*
Y0077257*
Y0077311*
Y0077365*
Y0077419*
Y0077473*
Y0077527*
Y0077582*
Y0077636*
Y007769*
Y0077744*
Y0077798*
Y0077852*
Y0077906*
Y007796*
Y0078014*
Y0078068*
Y0078122*
Y0078176*
Y007823*
Y0078284*
Y0078338*
Y0078392*
Y0078447*
Y00785*
Y0078555*
Y0078609*
Y0078663*
Y0078717*
Y0078771*
Y0078825*
Y0078879*
Y0078933*
Y0078987*
Y0079041*
Y0079095*
Y0079149*
Y0079203*
Y0079257*
Y0079312*
Y0079365*
Y007942*
Y0079474*
Y0079528*
Y0079582*
Y0079636*
Y007969*
Y0079744*
Y0079798*
Y0079852*
Y0079906*
Y007996*
Y0080014*
Y0080068*
Y0080122*
Y0080177*
Y008023*
Y0080285*
Y0080339*
Y0080393*
Y0080447*
Y0080501*
Y0080555*
Y0080609*
Y0080663*
Y0080717*
Y0080771*
Y0080825*
Y0080879*
Y0080933*
Y0080987*
Y0081042*
Y0081095*
Y008115*
Y0081204*
Y0081258*
Y0081312*
Y0081366*
Y008142*
Y0081474*
Y0081528*
Y0081582*
Y0081636*
Y008169*
Y0081744*
Y0081798*
Y0081852*
Y0081906*
Y008196*
Y0082015*
Y0082069*
Y0082123*
Y0082177*
Y0082231*
Y0082285*
Y0082339*
Y0082393*
Y0082447*
Y0082501*
Y0082555*
Y0082609*
Y0082663*
Y0082717*
Y0082771*
Y0082825*
Y008288*
Y0082934*
Y0082988*
Y0083042*
Y0083096*
Y008315*
Y0083204*
Y0083258*
Y0083312*
Y0083366*
Y008342*
Y0083474*
Y0083528*
Y0083582*
Y0083636*
Y0083691*
Y0083745*
Y0083799*
Y0083853*
Y0083907*
Y0083961*
Y0084015*
Y0084069*
Y0084123*
Y0084177*
Y0084231*
Y0084285*
Y0084339*
Y0084393*
Y0084447*
Y0084501*
Y0084556*
Y008461*
Y0084664*
Y0084718*
Y0084772*
Y0084826*
Y008488*
Y0084934*
Y0084988*
Y0085042*
Y0085096*
Y008515*
Y0085204*
Y0085258*
Y0085312*
Y0085366*
Y0085421*
Y0085474*
Y0085529*
Y0085583*
Y0085637*
Y0085691*
Y0085745*
Y0085799*
Y0085853*
Y0085907*
Y0085961*
Y0086015*
Y0086069*
Y0086123*
Y0086177*
Y0086231*
Y0086286*
Y0086339*
Y0086394*
Y0086448*
Y0086502*
Y0086556*
Y008661*
Y0086664*
Y0086718*
Y0086772*
Y0086826*
Y008688*
Y0086934*
Y0086988*
Y0087042*
Y0087096*
Y0087151*
Y0087204*
Y0087259*
Y0087313*
Y0087367*
Y0087421*
Y0087475*
Y0087529*
Y0087583*
Y0087637*
Y0087691*
Y0087745*
Y0087799*
Y0087853*
Y0087907*
Y0087961*
Y0088016*
Y0088069*
Y0088124*
Y0088178*
Y0088232*
Y0088286*
Y008834*
Y0088394*
Y0088448*
Y0088502*
Y0088556*
Y008861*
Y0088664*
Y0088718*
Y0088772*
Y0088826*
Y008888*
Y0088934*
Y0088989*
Y0089043*
Y0089097*
Y0089151*
Y0089205*
Y0089259*
Y0089313*
Y0089367*
Y0089421*
Y0089475*
Y0089529*
Y0089583*
Y0089637*
Y0089691*
Y0089745*
Y0089799*
Y0089854*
Y0089908*
Y0089962*
Y0090016*
Y009007*
Y0090124*
Y0090178*
Y0090232*
Y0090286*
Y009034*
Y0090394*
Y0090448*
Y0090502*
Y0090556*
Y009061*
Y0090664*
Y0090719*
Y0090773*
Y0090827*
Y0090881*
Y0090935*
Y0090989*
Y0091043*
Y0091097*
Y0091151*
Y0091205*
Y0091259*
Y0091313*
Y0091367*
Y0091421*
Y0091475*
Y009153*
Y0091584*
Y0091638*
Y0091692*
Y0091746*
Y00918*
Y0091854*
Y0091908*
Y0091962*
Y0092016*
Y009207*
Y0092124*
Y0092178*
Y0092232*
Y0092286*
Y009234*
Y0092395*
Y0092449*
Y0092503*
Y0092557*
Y0092611*
Y0092665*
Y0092719*
Y0092773*
Y0092827*
Y0092881*
Y0092935*
Y0092989*
Y0093043*
Y0093097*
Y0093151*
Y0093205*
Y009326*
Y0093313*
Y0093368*
Y0093422*
Y0093476*
Y009353*
Y0093584*
Y0093638*
Y0093692*
Y0093746*
Y00938*
Y0093854*
Y0093908*
Y0093962*
Y0094016*
Y009407*
Y0094125*
Y0094178*
Y0094233*
Y0094287*
Y0094341*
Y0094395*
Y0094449*
Y0094503*
Y0094557*
Y0094611*
Y0094665*
Y0094719*
Y0094773*
Y0094827*
Y0094881*
Y0094935*
Y009499*
Y0095043*
Y0095098*
Y0095152*
Y0095206*
Y009526*
Y0095314*
Y0095368*
Y0095422*
Y0095476*
Y009553*
Y0095584*
Y0095638*
Y0095692*
Y0095746*
Y00958*
Y0095854*
Y0095908*
Y0095963*
Y0096017*
Y0096071*
Y0096125*
Y0096179*
Y0096233*
Y0096287*
Y0096341*
Y0096395*
Y0096449*
Y0096503*
Y0096557*
Y0096611*
Y0096665*
Y0096719*
Y0096773*
Y0096828*
Y0096882*
Y0096936*
Y009699*
Y0097044*
Y0097098*
Y0097152*
Y0097206*
Y009726*
Y0097314*
Y0097368*
Y0097422*
Y0097476*
Y009753*
Y0097584*
Y0097638*
Y0097693*
Y0097747*
Y0097801*
Y0097855*
Y0097909*
Y0097963*
Y0098017*
Y0098071*
Y0098125*
Y0098179*
Y0098233*
Y0098287*
Y0098341*
Y0098395*
Y0098449*
Y0098504*
Y0098558*
Y0098612*
Y0098666*
Y009872*
Y0098774*
Y0098828*
Y0098882*
Y0098936*
Y009899*
Y0099044*
Y0099098*
Y0099152*
Y0099206*
Y009926*
Y0099314*
Y0099369*
Y0099423*
Y0099477*
Y0099531*
Y0099585*
Y0099639*
Y0099693*
Y0099747*
Y0099801*
Y0099855*
Y0099909*
Y0099963*
Y0100017*
Y0100071*
Y0100125*
Y0100179*
Y0100233*
Y0100287*
Y0100342*
Y0100396*
Y010045*
Y0100504*
Y0100558*
Y0100612*
Y0100666*
Y010072*
Y0100774*
Y0100828*
Y0100882*
Y0100936*
Y010099*
Y0101044*
Y0101099*
Y0101153*
Y0101207*
Y0101261*
Y0101315*
Y0101369*
Y0101423*
Y0101477*
Y0101531*
Y0101585*
Y0101639*
Y0101693*
Y0101747*
Y0101801*
Y0101855*
Y0101909*
Y0101963*
Y0102017*
Y0102072*
Y0102126*
Y010218*
Y0102234*
Y0102288*
Y0102342*
Y0102396*
Y010245*
Y0102504*
Y0102558*
Y0102612*
Y0102666*
Y010272*
Y0102774*
Y0102828*
Y0102883*
Y0102937*
Y0102991*
Y0103045*
Y0103099*
Y0103153*
Y0103207*
Y0103261*
Y0103315*
Y0103369*
Y0103423*
Y0103477*
Y0103531*
Y0103585*
Y0103639*
Y0103693*
Y0103747*
Y0103802*
Y0103856*
Y010391*
Y0103964*
Y0104018*
Y0104072*
Y0104126*
Y010418*
Y0104234*
Y0104288*
Y0104342*
Y0104396*
Y010445*
Y0104504*
Y0104558*
Y0104613*
Y0104667*
Y0104721*
Y0104775*
Y0104829*
Y0104883*
Y0104937*
Y0104991*
Y0105045*
Y0105099*
Y0105153*
Y0105207*
Y0105261*
Y0105315*
Y0105369*
Y0105423*
Y0105477*
Y0105532*
Y0105586*
Y010564*
Y0105694*
Y0105748*
Y0105802*
Y0105856*
Y010591*
Y0105964*
Y0106018*
Y0106072*
Y0106126*
Y010618*
Y0106234*
Y0106288*
Y0106342*
Y0106397*
Y0106451*
Y0106505*
Y0106559*
Y0106613*
Y0106667*
Y0106721*
Y0106775*
Y0106829*
Y0106883*
Y0106937*
Y0106991*
Y0107045*
Y0107099*
Y0107153*
Y0107208*
Y0107262*
Y0107316*
Y010737*
Y0107424*
Y0107478*
Y0107532*
Y0107586*
Y010764*
Y0107694*
Y0107748*
Y0107802*
Y0107856*
Y010791*
Y0107964*
Y0108018*
Y0108072*
Y0108126*
Y0108181*
Y0108235*
Y0108289*
Y0108343*
Y0108397*
Y0108451*
Y0108505*
Y0108559*
Y0108613*
Y0108667*
Y0108721*
Y0108775*
Y0108829*
Y0108883*
Y0108938*
Y0108992*
Y0109046*
Y01091*
Y0109154*
Y0109208*
Y0109262*
Y0109316*
Y010937*
Y0109424*
Y0109478*
Y0109532*
Y0109586*
Y010964*
Y0109694*
Y0109748*
Y0109802*
Y0109856*
Y0109911*
Y0109965*
Y0110019*
Y0110073*
Y0110127*
Y0110181*
Y0110235*
Y0110289*
Y0110343*
Y0110397*
Y0110451*
Y0110505*
Y0110559*
Y0110613*
Y0110668*
Y0110722*
Y0110776*
Y011083*
Y0110884*
Y0110938*
Y0110992*
Y0111046*
Y01111*
Y0111154*
Y0111208*
Y0111262*
Y0111316*
Y011137*
Y0111424*
Y0111478*
Y0111532*
Y0111586*
Y0111641*
Y0111695*
Y0111749*
Y0111803*
Y0111857*
Y0111911*
Y0111965*
Y0112019*
Y0112073*
Y0112127*
Y0112181*
Y0112235*
Y0112289*
Y0112343*
Y0112397*
Y0112452*
Y0112505*
Y011256*
Y0112614*
Y0112668*
Y0112722*
Y0112776*
Y011283*
Y0112884*
Y0112938*
Y0112992*
Y0113046*
Y01131*
Y0113154*
Y0113208*
Y0113262*
Y0113317*
Y0113371*
Y0113425*
Y0113479*
Y0113533*
Y0113587*
Y0113641*
Y0113695*
Y0113749*
Y0113803*
Y0113857*
Y0113911*
Y0113965*
Y0114019*
Y0114073*
Y0114127*
Y0114181*
Y0114235*
Y0114251*
X0590213Y0114298*
X0590197Y0114348*
X0590186Y01144*
X0590183Y0114452*
Y0114506*
Y0114521*
Y0114522*
X059016Y0114569*
X0590153Y0114587*
X0590149Y0114599*
X0590129Y011463*
X0590105Y0114677*
X0590095Y0114707*
X0590074Y0114738*
X0590051Y0114785*
X0590045Y0114804*
X059003Y0114817*
X0589995Y0114857*
X0589966Y01149*
X0589943Y0114947*
X0589937Y0114966*
X0589922Y0114979*
X0589909Y0114994*
X058989Y0115*
X0589843Y0115024*
X0589799Y0115053*
X058976Y0115087*
X0589747Y0115102*
X0589728Y0115109*
X0589681Y0115132*
X058966Y0115146*
X058965Y0115152*
X0589619Y0115163*
X0589572Y0115186*
X0589542Y0115207*
X0589511Y0115217*
X0589464Y011524*
X0589449*
X0589396Y0115244*
X0589345Y0115254*
X0589295Y0115271*
X0589248Y0115294*
X0582583*
X058253Y0115298*
X0582479Y0115308*
X0582429Y0115325*
X0582382Y0115348*
X0582339Y0115377*
X0582299Y0115412*
X0582265Y0115451*
X0582235Y0115495*
X0582212Y0115542*
X0582196Y0115592*
X0582185Y0115643*
X0582182Y0115695*
Y0115749*
Y0115803*
Y0115857*
Y0115911*
Y0115965*
Y011602*
Y0116074*
Y0116128*
Y0116182*
Y0116236*
Y011629*
Y0116344*
Y0116398*
Y0116452*
Y0116506*
Y011656*
Y0116614*
Y0116668*
Y0116722*
Y0116776*
Y0116831*
Y0116885*
Y0116939*
Y0116993*
Y0117047*
Y0117101*
Y0117155*
Y0117209*
Y0117263*
Y0117317*
Y0117371*
Y0117425*
Y0117479*
Y0117533*
Y0117587*
Y0117641*
Y0117695*
Y011775*
X0582185Y0117802*
X0582196Y0117853*
X0582212Y0117903*
X0582235Y011795*
X0582265Y0117994*
X0582299Y0118033*
X0582339Y0118068*
X0582382Y0118097*
X0582429Y011812*
X0582479Y0118137*
X058253Y0118147*
X0582583Y011815*
X0589449*
X0589501Y0118147*
G37*
%LNtimecard-dc-beta-v1-2*%
%LPC*%
G36*
X0638768Y0104158D02*
X0632845D01*
X0632844Y0104157*
X0632797Y0104134*
X0632748Y0104117*
X0632696Y0104107*
X0632644Y0104104*
X0632575*
X0632574Y0104103*
X0632527Y010408*
X0632478Y0104063*
X0632426Y0104053*
X0632417Y0104052*
X0632412Y0104049*
X0632365Y0104026*
X0632346Y0104019*
X0632333Y0104005*
X0632304Y0103979*
X0632279Y0103951*
X063225Y0103925*
X0632225Y0103897*
X0632196Y0103871*
X0632171Y0103842*
X0632142Y0103817*
X0632117Y0103788*
X0632092Y0103767*
X0632088Y0103763*
X0632063Y0103734*
X0632034Y0103709*
X0632009Y010368*
X063198Y0103655*
X0631964Y0103637*
X0631954Y0103626*
X0631926Y0103601*
X06319Y0103572*
X0631872Y0103547*
X0631846Y0103518*
X0631817Y0103493*
X0631792Y0103464*
X0631764Y0103439*
X0631746Y0103419*
X0631738Y010341*
X0631709Y0103385*
X0631684Y0103356*
X0631655Y0103331*
X063163Y0103302*
X0631601Y0103277*
X0631576Y0103248*
X0631547Y0103223*
X0631522Y0103194*
X0631493Y0103168*
X0631487Y0103162*
X0631468Y010314*
X0631439Y0103114*
X0631414Y0103086*
X0631385Y010306*
X063136Y0103032*
X0631331Y0103006*
X0631306Y0102978*
X0631277Y0102952*
X0631252Y0102923*
X0631223Y0102898*
X0631198Y0102869*
X0631169Y0102844*
X0631144Y0102815*
X0631122Y0102797*
X0631115Y010279*
X0631089Y0102761*
X0631061Y0102736*
X0631035Y0102707*
X0631007Y0102682*
X0630981Y0102653*
X0630953Y0102628*
X0630931Y0102603*
X0630928Y0102586*
X0630923Y0102562*
X0630906Y0102513*
X0630883Y0102466*
Y0102465*
Y010245*
Y0102396*
X0630879Y0102344*
X0630869Y0102292*
X0630852Y0102243*
X0630829Y0102196*
X0630828Y0102195*
Y010218*
Y0102126*
Y0102072*
Y0102017*
Y0101963*
Y0101909*
Y0101855*
Y0101801*
Y0101747*
Y0101693*
Y0101639*
Y0101585*
Y0101531*
Y0101477*
Y0101423*
Y0101369*
Y0101315*
Y0101261*
Y0101207*
Y0101153*
Y0101099*
Y0101044*
Y010099*
Y0100936*
Y0100882*
Y0100828*
Y0100774*
Y010072*
Y0100666*
Y0100612*
Y0100558*
Y0100504*
Y010045*
Y0100396*
Y0100342*
Y0100287*
Y0100233*
Y0100179*
Y0100125*
Y0100071*
Y0100017*
Y0099963*
Y0099909*
Y0099855*
Y0099801*
Y0099747*
Y0099693*
Y0099639*
Y0099585*
Y0099531*
Y0099477*
Y0099423*
Y0099369*
Y0099314*
Y009926*
Y0099206*
Y0099152*
Y0099098*
Y0099044*
Y009899*
Y0098936*
Y0098882*
Y0098828*
Y0098774*
Y009872*
Y0098666*
Y0098612*
Y0098558*
Y0098504*
Y0098449*
Y0098395*
Y0098341*
Y0098287*
Y0098233*
Y0098179*
Y0098125*
Y0098071*
Y0098017*
Y0097963*
Y0097909*
Y0097855*
Y0097801*
Y0097747*
Y0097693*
Y0097638*
Y0097584*
Y009753*
Y0097476*
Y0097422*
Y0097368*
Y0097314*
Y009726*
Y0097206*
Y0097152*
Y0097098*
Y0097044*
Y009699*
Y0096936*
Y0096882*
Y0096828*
Y0096773*
Y0096719*
Y0096665*
Y0096611*
Y0096557*
Y0096503*
Y0096449*
Y0096395*
Y0096341*
Y0096287*
Y0096233*
Y0096179*
Y0096125*
Y0096071*
Y0096017*
Y0095963*
Y0095908*
Y0095854*
Y00958*
Y0095746*
Y0095692*
Y0095638*
Y0095584*
Y009553*
Y0095476*
Y0095422*
Y0095368*
Y0095314*
Y009526*
Y0095206*
Y0095152*
Y0095098*
Y0095082*
X0630829*
X0630852Y0095035*
X0630869Y0094985*
X0630879Y0094934*
X0630883Y0094881*
Y0094827*
Y0094812*
Y0094811*
X0630906Y0094764*
X0630916Y0094734*
X0630937Y0094703*
X063096Y0094656*
X0630967Y0094637*
X0630981Y0094624*
X0631007Y0094595*
X0631035Y009457*
X0631061Y0094541*
X0631089Y0094516*
X0631115Y0094487*
X0631144Y0094462*
X0631169Y0094433*
X0631198Y0094408*
X0631223Y0094379*
X0631245Y009436*
X0631252Y0094354*
X0631277Y0094325*
X0631306Y00943*
X0631331Y0094271*
X063136Y0094246*
X0631385Y0094217*
X0631414Y0094192*
X0631439Y0094163*
X0631468Y0094138*
X0631493Y0094109*
X0631522Y0094084*
X0631547Y0094055*
X0631576Y0094029*
X0631601Y0094001*
X063163Y0093975*
X0631655Y0093947*
X0631684Y0093921*
X0631709Y0093893*
X0631738Y0093867*
X0631764Y0093839*
X0631792Y0093813*
X0631817Y0093784*
X0631843Y0093762*
X0631846Y0093759*
X0631872Y009373*
X06319Y0093705*
X0631926Y0093676*
X0631952Y0093654*
X0631954Y0093651*
X063198Y0093622*
X0632009Y0093597*
X0632034Y0093568*
X0632063Y0093543*
X0632088Y0093514*
X0632117Y0093489*
X0632142Y009346*
X0632171Y0093435*
X0632196Y0093406*
X0632225Y0093381*
X063225Y0093352*
X0632279Y0093327*
X0632304Y0093298*
X0632333Y0093273*
X0632346Y0093258*
X0632365Y0093251*
X0632412Y0093228*
X0632413*
X0632428*
X063248Y0093224*
X0632532Y0093214*
X0632581Y0093197*
X0632628Y0093174*
X0632629*
X0639047*
X0639055Y009319*
Y0093205*
Y009326*
Y0093313*
Y0093368*
Y0093422*
Y0093476*
Y009353*
Y0093584*
Y0093638*
Y0093692*
Y0093746*
Y00938*
Y0093854*
Y0093908*
Y0093962*
Y0094016*
Y009407*
Y0094125*
Y0094178*
Y0094233*
Y0094287*
Y0094341*
Y0094395*
Y0094449*
Y0094503*
Y0094557*
Y0094611*
Y0094665*
Y0094719*
Y0094773*
Y0094827*
Y0094881*
Y0094935*
Y009499*
Y0095043*
Y0095098*
Y0095113*
X063905Y0095124*
X0639039Y0095129*
X0633455*
X0633403Y0095133*
X0633351Y0095143*
X0633302Y009516*
X0633255Y0095183*
X0633211Y0095212*
X0633172Y0095247*
X0633154Y0095266*
X0633146Y0095275*
X0633117Y0095301*
X0633083Y009534*
X0633054Y0095384*
X0633031Y0095431*
X0633014Y009548*
X0633004Y0095532*
X0633Y0095584*
Y0095638*
Y0095692*
Y0095746*
Y00958*
Y0095854*
Y0095908*
Y0095963*
Y0096017*
Y0096071*
Y0096125*
Y0096179*
Y0096233*
Y0096287*
Y0096341*
Y0096395*
Y0096449*
Y0096503*
Y0096557*
Y0096611*
Y0096665*
Y0096719*
Y0096773*
Y0096828*
Y0096882*
Y0096936*
Y009699*
Y0097044*
Y0097098*
Y0097152*
Y0097206*
Y009726*
Y0097314*
Y0097368*
Y0097422*
X0633004Y0097475*
X0633014Y0097526*
X0633031Y0097576*
X0633054Y0097623*
X0633083Y0097666*
X0633117Y0097706*
X0633146Y0097731*
X0633172Y009776*
X0633211Y0097794*
X0633255Y0097824*
X0633302Y0097847*
X0633351Y0097864*
X0633403Y0097874*
X0633455Y0097877*
X063819*
Y0097909*
Y0097963*
Y0098017*
Y0098071*
Y0098125*
Y0098179*
Y0098233*
Y0098287*
Y0098341*
Y0098395*
Y0098449*
Y0098504*
Y0098558*
Y0098612*
Y0098666*
Y009872*
Y0098774*
Y0098828*
Y0098882*
Y0098936*
Y009899*
Y0099044*
Y0099098*
Y0099152*
Y0099206*
Y009926*
Y0099314*
Y0099369*
Y00994*
X0633455*
X0633403Y0099404*
X0633351Y0099414*
X0633302Y0099431*
X0633255Y0099454*
X0633211Y0099483*
X0633172Y0099518*
X0633146Y0099546*
X0633117Y0099572*
X0633083Y0099611*
X0633054Y0099655*
X0633031Y0099702*
X0633014Y0099751*
X0633004Y0099803*
X0633Y0099855*
Y0099909*
Y0099963*
Y0100017*
Y0100071*
Y0100125*
Y0100179*
Y0100233*
Y0100287*
Y0100342*
Y0100396*
Y010045*
Y0100504*
Y0100558*
Y0100612*
Y0100666*
Y010072*
Y0100774*
Y0100828*
Y0100882*
Y0100936*
Y010099*
Y0101044*
Y0101099*
Y0101153*
Y0101207*
Y0101261*
Y0101315*
Y0101369*
Y0101423*
Y0101477*
Y0101531*
Y0101585*
Y0101639*
Y0101693*
Y0101747*
X0633004Y0101799*
X0633014Y0101851*
X0633031Y0101901*
X0633054Y0101948*
X0633083Y0101991*
X0633117Y0102031*
X0633146Y0102056*
X0633172Y0102085*
X0633211Y0102119*
X0633255Y0102148*
X0633302Y0102172*
X0633351Y0102189*
X0633403Y0102199*
X0633455Y0102202*
X0639055*
Y0102234*
Y0102288*
Y0102342*
Y0102396*
Y010245*
Y0102504*
Y0102558*
Y0102612*
Y0102666*
Y010272*
Y0102774*
Y0102828*
Y0102883*
Y0102937*
Y0102991*
Y0103045*
Y0103099*
Y0103153*
Y0103207*
Y0103261*
Y0103315*
Y0103369*
Y0103423*
Y0103477*
Y0103531*
Y0103585*
Y0103639*
Y0103693*
Y0103747*
Y0103802*
Y0103856*
Y010391*
Y0103964*
Y0104018*
Y0104072*
Y0104087*
Y0104088*
X0639046Y0104105*
X0639023Y0104104*
X0638969*
X0638917Y0104107*
X0638866Y0104117*
X0638816Y0104134*
X0638769Y0104157*
X0638768Y0104158*
G37*
G36*
X0624891D02*
X0617221D01*
Y0104157*
X0617174Y0104134*
X0617151Y0104126*
Y0104072*
Y0104018*
Y0103964*
Y010391*
Y0103856*
Y0103802*
Y0103747*
Y0103693*
Y0103639*
Y0103585*
Y0103531*
Y0103477*
Y0103423*
Y0103369*
Y0103315*
Y0103261*
Y0103207*
Y0103153*
Y0103099*
Y0103045*
Y0102991*
Y0102937*
Y0102883*
Y0102828*
Y0102774*
Y010272*
Y0102666*
Y0102612*
Y0102558*
Y0102504*
Y010245*
Y0102396*
Y0102342*
Y0102288*
Y0102234*
Y010218*
Y0102126*
Y0102072*
Y0102017*
Y0101963*
Y0101909*
Y0101855*
Y0101801*
Y0101747*
Y0101693*
Y0101639*
Y0101585*
Y0101531*
Y0101477*
Y0101423*
Y0101369*
Y0101315*
Y0101261*
Y0101207*
Y0101153*
Y0101099*
Y0101044*
Y010099*
Y0100936*
Y0100882*
Y0100828*
Y0100774*
Y010072*
Y0100666*
Y0100612*
Y0100558*
Y0100504*
Y010045*
Y0100396*
Y0100342*
Y0100287*
Y0100233*
Y0100179*
Y0100125*
Y0100071*
Y0100017*
Y0099963*
Y0099909*
Y0099855*
Y0099801*
Y0099747*
Y0099693*
Y0099639*
Y0099585*
Y0099531*
Y0099477*
Y0099423*
Y0099369*
Y0099314*
Y009926*
Y0099206*
Y0099152*
Y0099098*
Y0099044*
Y009899*
Y0098936*
Y0098882*
Y0098828*
Y0098774*
Y009872*
Y0098666*
Y0098612*
Y0098558*
Y0098504*
Y0098449*
Y0098395*
Y0098341*
Y0098287*
Y0098233*
Y0098179*
Y0098125*
Y0098071*
Y0098017*
Y0097963*
Y0097909*
Y0097855*
Y0097801*
Y0097747*
Y0097693*
Y0097638*
Y0097584*
Y009753*
Y0097476*
Y0097422*
Y0097368*
Y0097314*
Y009726*
Y0097206*
Y0097152*
Y0097098*
Y0097044*
Y009699*
Y0096936*
Y0096882*
Y0096828*
Y0096773*
Y0096719*
Y0096665*
Y0096611*
Y0096557*
Y0096503*
Y0096449*
Y0096395*
Y0096341*
Y0096287*
Y0096233*
Y0096179*
Y0096125*
Y0096071*
Y0096017*
Y0095963*
Y0095908*
Y0095854*
Y00958*
Y0095746*
Y0095692*
Y0095638*
Y0095584*
Y009553*
Y0095476*
Y0095422*
Y0095368*
Y0095314*
Y009526*
Y0095206*
Y0095152*
Y0095098*
Y0095043*
Y009499*
Y0094935*
Y0094881*
Y0094827*
Y0094773*
Y0094719*
Y0094665*
Y0094611*
Y0094557*
Y0094503*
Y0094449*
Y0094395*
Y0094341*
Y0094287*
Y0094233*
Y0094178*
Y0094125*
Y009407*
Y0094016*
Y0093962*
Y0093908*
Y0093854*
Y00938*
Y0093746*
Y0093692*
Y0093638*
Y0093584*
Y009353*
Y0093476*
Y0093422*
Y0093368*
Y0093313*
Y009326*
Y0093205*
Y0093174*
X0619314*
X0619322Y009319*
Y0093205*
Y009326*
Y0093313*
Y0093368*
Y0093422*
Y0093476*
Y009353*
Y0093584*
Y0093638*
Y0093692*
Y0093746*
Y00938*
Y0093854*
Y0093908*
Y0093962*
Y0094016*
Y009407*
Y0094125*
Y0094178*
Y0094233*
Y0094287*
Y0094341*
Y0094395*
Y0094449*
Y0094503*
Y0094557*
Y0094611*
Y0094665*
Y0094719*
Y0094773*
Y0094827*
Y0094881*
Y0094935*
Y009499*
Y0095043*
Y0095098*
Y0095152*
Y0095206*
Y009526*
Y0095314*
Y0095368*
Y0095422*
Y0095476*
Y009553*
Y0095584*
Y0095638*
Y0095692*
Y0095746*
Y00958*
Y0095854*
Y0095908*
Y0095963*
Y0096017*
Y0096071*
Y0096125*
Y0096179*
Y0096233*
Y0096287*
Y0096341*
Y0096395*
Y0096449*
Y0096503*
Y0096557*
Y0096611*
Y0096665*
Y0096719*
Y0096773*
Y0096828*
Y0096882*
Y0096936*
Y009699*
Y0097044*
Y0097098*
Y0097152*
Y0097206*
Y009726*
Y0097314*
Y0097368*
Y0097422*
Y0097476*
Y009753*
Y0097584*
Y0097638*
Y0097693*
Y0097747*
Y0097801*
Y0097855*
Y0097909*
Y0097963*
Y0098017*
Y0098071*
Y0098125*
Y0098179*
Y0098233*
Y0098287*
Y0098341*
Y0098395*
Y0098449*
Y0098504*
Y0098558*
Y0098612*
Y0098666*
Y009872*
Y0098774*
Y0098828*
Y0098882*
Y0098936*
Y009899*
Y0099044*
Y0099098*
Y0099152*
Y0099206*
Y009926*
Y0099314*
Y0099369*
Y0099423*
Y0099477*
Y0099531*
Y0099585*
Y0099639*
Y0099693*
Y0099747*
Y0099801*
Y0099855*
Y0099909*
Y0099963*
Y0100017*
Y0100071*
Y0100125*
Y0100179*
Y0100233*
Y0100287*
Y0100342*
Y0100396*
Y010045*
Y0100504*
Y0100558*
Y0100612*
Y0100666*
Y010072*
Y0100774*
Y0100828*
Y0100882*
Y0100936*
Y010099*
Y0101044*
Y0101099*
Y0101153*
Y0101207*
Y0101261*
Y0101315*
Y0101369*
Y0101423*
Y0101477*
Y0101531*
Y0101585*
Y0101639*
X0619326Y0101691*
X0619336Y0101743*
X0619353Y0101793*
X0619376Y0101839*
X0619405Y0101883*
X061944Y0101923*
X0619479Y0101957*
X0619523Y0101986*
X061957Y0102009*
X061962Y0102026*
X0619671Y0102036*
X0619723Y010204*
X0621561*
X0621614Y0102036*
X0621665Y0102026*
X0621715Y0102009*
X0621762Y0101986*
X0621805Y0101957*
X0621845Y0101923*
X0621879Y0101883*
X0621909Y0101839*
X0621932Y0101793*
X0621949Y0101743*
X0621959Y0101691*
X0621962Y0101639*
Y0101585*
Y0101531*
Y0101477*
Y0101423*
Y0101369*
Y0101315*
Y0101261*
Y0101207*
Y0101153*
Y0101099*
Y0101044*
Y010099*
Y0100936*
Y0100882*
Y0100828*
Y0100774*
Y010072*
Y0100666*
Y0100612*
Y0100558*
Y0100504*
Y010045*
Y0100396*
Y0100342*
Y0100287*
Y0100233*
Y0100179*
Y0100125*
Y0100071*
Y0100017*
Y0099963*
Y0099909*
Y0099855*
Y0099801*
Y0099747*
Y0099693*
Y0099639*
Y0099585*
Y0099531*
Y0099477*
Y0099423*
Y0099369*
Y0099314*
Y009926*
Y0099206*
Y0099152*
Y0099098*
Y0099044*
Y009899*
Y0098936*
Y0098882*
Y0098828*
Y0098774*
Y009872*
Y0098666*
Y0098612*
Y0098558*
Y0098504*
Y0098449*
Y0098395*
Y0098341*
Y0098287*
Y0098233*
Y0098179*
Y0098125*
Y0098071*
Y0098017*
Y0097963*
Y0097909*
Y0097855*
Y0097801*
Y0097747*
Y0097693*
Y0097638*
Y0097584*
Y009753*
Y0097476*
Y0097422*
Y0097368*
Y0097314*
Y009726*
Y0097206*
Y0097152*
Y0097098*
Y0097044*
Y009699*
Y0096936*
Y0096882*
Y0096828*
Y0096773*
Y0096719*
Y0096665*
Y0096611*
Y0096557*
Y0096503*
Y0096449*
Y0096395*
Y0096341*
Y0096287*
Y0096233*
Y0096179*
Y0096125*
Y0096071*
Y0096017*
Y0095963*
Y0095908*
Y0095854*
Y00958*
Y0095746*
Y0095692*
Y0095638*
Y0095584*
Y009553*
Y0095476*
Y0095422*
Y0095368*
Y0095314*
Y009526*
Y0095206*
Y0095152*
Y0095098*
Y0095043*
Y009499*
Y0094935*
Y0094881*
Y0094827*
Y0094773*
Y0094719*
Y0094665*
Y0094611*
Y0094557*
Y0094503*
Y0094449*
Y0094395*
Y0094341*
Y0094287*
Y0094233*
Y0094178*
Y0094125*
Y009407*
Y0094016*
Y0093962*
Y0093908*
Y0093854*
Y00938*
Y0093746*
Y0093692*
Y0093638*
Y0093584*
Y009353*
Y0093476*
Y0093422*
Y0093368*
Y0093313*
Y009326*
Y0093205*
Y009319*
X0621963*
X0621968Y0093179*
X0621978Y0093174*
X0621979*
X0623918*
Y0093205*
Y009326*
Y0093313*
Y0093368*
Y0093422*
Y0093476*
Y009353*
Y0093584*
Y0093638*
Y0093692*
Y0093746*
Y00938*
Y0093854*
Y0093908*
Y0093962*
Y0094016*
Y009407*
Y0094125*
Y0094178*
Y0094233*
Y0094287*
Y0094341*
Y0094395*
Y0094449*
Y0094503*
Y0094557*
Y0094611*
Y0094665*
Y0094719*
Y0094773*
Y0094827*
Y0094881*
Y0094935*
Y009499*
Y0095043*
Y0095098*
Y0095152*
Y0095206*
Y009526*
Y0095314*
Y0095368*
Y0095422*
Y0095476*
Y009553*
Y0095584*
Y0095638*
Y0095692*
Y0095746*
Y00958*
Y0095854*
Y0095908*
Y0095963*
Y0096017*
Y0096071*
Y0096125*
Y0096179*
Y0096233*
Y0096287*
Y0096341*
Y0096395*
Y0096449*
Y0096503*
Y0096557*
Y0096611*
Y0096665*
Y0096719*
Y0096773*
Y0096828*
Y0096882*
Y0096936*
Y009699*
Y0097044*
Y0097098*
Y0097152*
Y0097206*
Y009726*
Y0097314*
Y0097368*
Y0097422*
Y0097476*
Y009753*
Y0097584*
Y0097638*
Y0097693*
Y0097747*
Y0097801*
Y0097855*
Y0097909*
Y0097963*
Y0098017*
Y0098071*
Y0098125*
Y0098179*
Y0098233*
Y0098287*
Y0098341*
Y0098395*
Y0098449*
Y0098504*
Y0098558*
Y0098612*
Y0098666*
Y009872*
Y0098774*
Y0098828*
Y0098882*
Y0098936*
Y009899*
Y0099044*
Y0099098*
Y0099152*
Y0099206*
Y009926*
Y0099314*
Y0099369*
Y0099423*
Y0099477*
Y0099531*
Y0099585*
Y0099639*
Y0099693*
Y0099747*
Y0099801*
Y0099855*
Y0099909*
Y0099963*
Y0100017*
Y0100071*
Y0100125*
Y0100179*
Y0100233*
Y0100287*
Y0100342*
Y0100396*
Y010045*
Y0100504*
Y0100558*
Y0100612*
Y0100666*
Y010072*
Y0100774*
Y0100828*
Y0100882*
Y0100936*
Y010099*
Y0101044*
Y0101099*
Y0101153*
Y0101207*
Y0101261*
Y0101315*
Y0101369*
Y0101423*
Y0101477*
Y0101531*
Y0101585*
Y0101639*
X0623921Y0101691*
X0623931Y0101743*
X0623948Y0101793*
X0623971Y0101839*
X0624001Y0101883*
X0624035Y0101923*
X0624075Y0101957*
X0624118Y0101986*
X0624165Y0102009*
X0624215Y0102026*
X0624266Y0102036*
X0624319Y010204*
X0624874*
X0624875*
X0624891Y0102048*
Y0102072*
Y0102126*
Y010218*
Y0102234*
Y0102288*
Y0102342*
Y0102396*
Y010245*
Y0102504*
Y0102558*
Y0102612*
Y0102666*
Y010272*
Y0102774*
Y0102828*
Y0102883*
Y0102937*
Y0102991*
Y0103045*
Y0103099*
Y0103153*
Y0103207*
Y0103261*
Y0103315*
Y0103369*
Y0103423*
Y0103477*
Y0103531*
Y0103585*
Y0103639*
Y0103693*
Y0103747*
Y0103802*
Y0103856*
Y010391*
Y0103964*
Y0104018*
Y0104072*
Y0104126*
Y0104158*
G37*
G36*
X0614981D02*
X0612896D01*
Y0104157*
X0612849Y0104134*
X061283Y0104095*
X0612826Y0104088*
Y0104087*
Y0104072*
Y0104018*
Y0103964*
Y010391*
Y0103856*
Y0103802*
Y0103747*
Y0103693*
Y0103639*
Y0103585*
Y0103531*
Y0103477*
Y0103423*
Y0103369*
Y0103315*
Y0103261*
Y0103207*
Y0103153*
Y0103099*
Y0103045*
Y0102991*
Y0102937*
Y0102883*
Y0102828*
Y0102774*
Y010272*
Y0102666*
Y0102612*
Y0102558*
Y0102504*
Y010245*
Y0102396*
Y0102342*
Y0102288*
Y0102234*
Y010218*
Y0102126*
Y0102072*
Y0102017*
Y0101963*
Y0101909*
Y0101855*
Y0101801*
Y0101747*
Y0101693*
Y0101639*
Y0101585*
Y0101531*
Y0101477*
Y0101423*
Y0101369*
Y0101315*
Y0101261*
Y0101207*
Y0101153*
Y0101099*
Y0101044*
Y010099*
Y0100936*
Y0100882*
Y0100828*
Y0100774*
Y010072*
Y0100666*
Y0100612*
Y0100558*
Y0100504*
Y010045*
Y0100396*
Y0100342*
Y0100287*
Y0100233*
Y0100179*
Y0100125*
Y0100071*
Y0100017*
Y0099963*
Y0099909*
Y0099855*
Y0099801*
Y0099747*
Y0099693*
Y0099639*
Y0099585*
Y0099531*
Y0099477*
Y0099423*
Y0099369*
Y0099314*
Y009926*
Y0099206*
Y0099152*
Y0099098*
Y0099044*
Y009899*
Y0098936*
Y0098882*
Y0098828*
Y0098774*
Y009872*
Y0098666*
Y0098612*
Y0098558*
Y0098504*
Y0098449*
Y0098395*
Y0098341*
Y0098287*
Y0098233*
Y0098179*
Y0098125*
Y0098071*
Y0098017*
Y0097963*
Y0097909*
Y0097855*
Y0097801*
Y0097747*
Y0097693*
Y0097638*
Y0097584*
Y009753*
Y0097476*
Y0097422*
Y0097368*
Y0097314*
Y009726*
Y0097206*
Y0097152*
Y0097098*
Y0097044*
Y009699*
Y0096936*
Y0096882*
Y0096828*
Y0096773*
Y0096719*
Y0096665*
Y0096611*
Y0096557*
Y0096503*
Y0096449*
Y0096395*
Y0096341*
Y0096287*
Y0096233*
Y0096179*
Y0096125*
Y0096071*
Y0096017*
Y0095963*
Y0095908*
Y0095854*
Y00958*
Y0095746*
Y0095692*
Y0095638*
Y0095584*
Y009553*
Y0095476*
Y0095422*
Y0095368*
Y0095314*
Y009526*
Y0095206*
Y0095152*
Y0095098*
Y0095043*
Y009499*
Y0094935*
Y0094881*
Y0094827*
Y0094773*
Y0094719*
Y0094665*
Y0094611*
Y0094557*
Y0094503*
Y0094449*
Y0094395*
Y0094341*
Y0094287*
Y0094233*
Y0094178*
Y0094125*
Y009407*
Y0094016*
Y0093962*
Y0093908*
Y0093854*
Y00938*
Y0093746*
Y0093692*
Y0093638*
Y0093584*
Y009353*
Y0093476*
Y0093422*
Y0093368*
Y0093313*
Y009326*
Y0093205*
Y009319*
X0612834Y0093174*
X0614997*
Y0093205*
Y009326*
Y0093313*
Y0093368*
Y0093422*
Y0093476*
Y009353*
Y0093584*
Y0093638*
Y0093692*
Y0093746*
Y00938*
Y0093854*
Y0093908*
Y0093962*
Y0094016*
Y009407*
Y0094125*
Y0094178*
Y0094233*
Y0094287*
Y0094341*
Y0094395*
Y0094449*
Y0094503*
Y0094557*
Y0094611*
Y0094665*
Y0094719*
Y0094773*
Y0094827*
Y0094881*
Y0094935*
Y009499*
Y0095043*
Y0095098*
Y0095152*
Y0095206*
Y009526*
Y0095314*
Y0095368*
Y0095422*
Y0095476*
Y009553*
Y0095584*
Y0095638*
Y0095692*
Y0095746*
Y00958*
Y0095854*
Y0095908*
Y0095963*
Y0096017*
Y0096071*
Y0096125*
Y0096179*
Y0096233*
Y0096287*
Y0096341*
Y0096395*
Y0096449*
Y0096503*
Y0096557*
Y0096611*
Y0096665*
Y0096719*
Y0096773*
Y0096828*
Y0096882*
Y0096936*
Y009699*
Y0097044*
Y0097098*
Y0097152*
Y0097206*
Y009726*
Y0097314*
Y0097368*
Y0097422*
Y0097476*
Y009753*
Y0097584*
Y0097638*
Y0097693*
Y0097747*
Y0097801*
Y0097855*
Y0097909*
Y0097963*
Y0098017*
Y0098071*
Y0098125*
Y0098179*
Y0098233*
Y0098287*
Y0098341*
Y0098395*
Y0098449*
Y0098504*
Y0098558*
Y0098612*
Y0098666*
Y009872*
Y0098774*
Y0098828*
Y0098882*
Y0098936*
Y009899*
Y0099044*
Y0099098*
Y0099152*
Y0099206*
Y009926*
Y0099314*
Y0099369*
Y0099423*
Y0099477*
Y0099531*
Y0099585*
Y0099639*
Y0099693*
Y0099747*
Y0099801*
Y0099855*
Y0099909*
Y0099963*
Y0100017*
Y0100071*
Y0100125*
Y0100179*
Y0100233*
Y0100287*
Y0100342*
Y0100396*
Y010045*
Y0100504*
Y0100558*
Y0100612*
Y0100666*
Y010072*
Y0100774*
Y0100828*
Y0100882*
Y0100936*
Y010099*
Y0101044*
Y0101099*
Y0101153*
Y0101207*
Y0101261*
Y0101315*
Y0101369*
Y0101423*
Y0101477*
Y0101531*
Y0101585*
Y0101639*
Y0101693*
Y0101747*
Y0101801*
Y0101855*
Y0101909*
Y0101963*
Y0102017*
Y0102072*
Y0102126*
Y010218*
Y0102234*
Y0102288*
Y0102342*
Y0102396*
Y010245*
Y0102504*
Y0102558*
Y0102612*
Y0102666*
Y010272*
Y0102774*
Y0102828*
Y0102883*
Y0102937*
Y0102991*
Y0103045*
Y0103099*
Y0103153*
Y0103207*
Y0103261*
Y0103315*
Y0103369*
Y0103423*
Y0103477*
Y0103531*
Y0103585*
Y0103639*
Y0103693*
Y0103747*
Y0103802*
Y0103856*
Y010391*
Y0103964*
Y0104018*
Y0104072*
Y0104126*
Y0104149*
X0614982Y0104157*
X0614981Y0104158*
G37*
G36*
X0611143D02*
X0603219D01*
Y0104157*
X0603171Y0104134*
X0603149Y0104126*
Y0104072*
Y0104018*
Y0103964*
Y010391*
Y0103856*
Y0103802*
Y0103747*
Y0103693*
Y0103639*
Y0103585*
Y0103531*
Y0103477*
Y0103423*
Y0103369*
Y0103315*
Y0103261*
Y0103207*
Y0103153*
Y0103099*
Y0103045*
Y0102991*
Y0102937*
Y0102883*
Y0102828*
Y0102774*
Y010272*
Y0102666*
Y0102612*
Y0102558*
Y0102504*
Y010245*
Y0102396*
Y0102342*
Y0102288*
Y0102234*
Y010218*
Y0102126*
Y0102074*
X0603152Y010207*
X0603171Y0102064*
X0603219Y010204*
X0605613*
X0605665Y0102036*
X0605717Y0102026*
X0605766Y0102009*
X0605814Y0101986*
X0605857Y0101957*
X0605897Y0101923*
X0605922Y0101894*
X060594Y0101878*
X0605951Y0101868*
X0605976Y010184*
X0606005Y0101814*
X0606039Y0101775*
X0606068Y0101731*
X0606092Y0101684*
X0606102Y0101654*
X0606122Y0101623*
X0606146Y0101576*
X0606163Y0101527*
X0606173Y0101475*
X0606176Y0101423*
Y0101369*
Y0101315*
Y0101261*
Y0101207*
Y0101153*
Y0101099*
Y0101044*
Y010099*
Y0100936*
Y0100882*
Y0100828*
Y0100774*
Y010072*
Y0100666*
Y0100612*
Y0100558*
Y0100504*
Y010045*
Y0100396*
Y0100342*
Y0100287*
Y0100233*
Y0100179*
Y0100125*
Y0100071*
Y0100017*
Y0099963*
Y0099909*
Y0099855*
Y0099801*
Y0099747*
Y0099693*
Y0099639*
Y0099585*
Y0099531*
Y0099477*
Y0099423*
Y0099369*
Y0099314*
Y009926*
Y0099206*
Y0099152*
Y0099098*
Y0099044*
Y009899*
Y0098936*
Y0098882*
Y0098828*
Y0098774*
Y009872*
Y0098666*
Y0098612*
Y0098558*
Y0098504*
Y0098449*
Y0098395*
Y0098341*
Y0098287*
Y0098233*
Y0098179*
Y0098125*
Y0098071*
Y0098017*
Y0097963*
Y0097909*
Y0097855*
Y0097801*
Y0097747*
Y0097693*
Y0097638*
Y0097584*
Y009753*
Y0097476*
Y0097422*
Y0097368*
Y0097314*
Y009726*
Y0097206*
Y0097152*
Y0097098*
Y0097044*
Y009699*
Y0096936*
Y0096882*
Y0096828*
Y0096773*
Y0096719*
Y0096665*
Y0096611*
Y0096557*
Y0096503*
Y0096449*
Y0096395*
Y0096341*
Y0096287*
Y0096233*
Y0096179*
Y0096125*
Y0096071*
Y0096017*
Y0095963*
Y0095908*
Y0095854*
Y00958*
Y0095746*
Y0095692*
Y0095638*
Y0095584*
Y009553*
Y0095476*
Y0095422*
Y0095368*
Y0095314*
Y009526*
Y0095206*
Y0095152*
Y0095098*
Y0095043*
Y009499*
Y0094935*
Y0094881*
Y0094827*
Y0094773*
Y0094719*
Y0094665*
Y0094611*
Y0094557*
Y0094503*
Y0094449*
Y0094395*
Y0094341*
Y0094287*
Y0094233*
Y0094178*
Y0094125*
Y009407*
Y0094016*
Y0093962*
Y0093908*
Y0093854*
Y00938*
Y0093746*
Y0093692*
Y0093638*
Y0093584*
Y009353*
Y0093476*
Y0093422*
Y0093368*
Y0093313*
Y009326*
Y0093205*
Y0093174*
X0608317*
X0608324Y0093197*
X0608348Y0093244*
Y009326*
Y0093313*
Y0093368*
Y0093422*
Y0093476*
Y009353*
Y0093584*
Y0093638*
Y0093692*
Y0093746*
Y00938*
Y0093854*
Y0093908*
Y0093962*
Y0094016*
Y009407*
Y0094125*
Y0094178*
Y0094233*
Y0094287*
Y0094341*
Y0094395*
Y0094449*
Y0094503*
Y0094557*
Y0094611*
Y0094665*
Y0094719*
Y0094773*
Y0094827*
Y0094881*
Y0094935*
Y009499*
Y0095043*
Y0095098*
Y0095152*
Y0095206*
Y009526*
Y0095314*
Y0095368*
Y0095422*
Y0095476*
Y009553*
Y0095584*
Y0095638*
Y0095692*
Y0095746*
Y00958*
Y0095854*
Y0095908*
Y0095963*
Y0096017*
Y0096071*
Y0096125*
Y0096179*
Y0096233*
Y0096287*
Y0096341*
Y0096395*
Y0096449*
Y0096503*
Y0096557*
Y0096611*
Y0096665*
Y0096719*
Y0096773*
Y0096828*
Y0096882*
Y0096936*
Y009699*
Y0097044*
Y0097098*
Y0097152*
Y0097206*
Y009726*
Y0097314*
Y0097368*
Y0097422*
Y0097476*
Y009753*
Y0097584*
Y0097638*
Y0097693*
Y0097747*
Y0097801*
Y0097855*
Y0097909*
Y0097963*
Y0098017*
Y0098071*
Y0098125*
Y0098179*
Y0098233*
Y0098287*
Y0098341*
Y0098395*
Y0098449*
Y0098504*
Y0098558*
Y0098612*
Y0098666*
Y009872*
Y0098774*
Y0098828*
Y0098882*
Y0098936*
Y009899*
Y0099044*
Y0099098*
Y0099152*
Y0099206*
Y009926*
Y0099314*
Y0099369*
Y0099423*
Y0099477*
Y0099531*
Y0099585*
Y0099639*
Y0099693*
Y0099747*
Y0099801*
Y0099855*
Y0099909*
Y0099963*
Y0100017*
Y0100071*
Y0100125*
Y0100179*
Y0100233*
Y0100287*
Y0100342*
Y0100396*
Y010045*
Y0100504*
Y0100558*
Y0100612*
Y0100666*
Y010072*
Y0100774*
Y0100828*
Y0100882*
Y0100936*
Y010099*
Y0101044*
Y0101099*
Y0101153*
Y0101207*
Y0101261*
Y0101315*
Y0101369*
Y0101423*
Y0101477*
Y0101531*
X0608351Y0101583*
X0608361Y0101635*
X0608378Y0101684*
X0608401Y0101731*
X0608431Y0101775*
X0608465Y0101814*
X0608494Y010184*
X0608519Y0101868*
X0608548Y0101894*
X0608573Y0101923*
X0608613Y0101957*
X0608656Y0101986*
X0608703Y0102009*
X0608753Y0102026*
X0608805Y0102036*
X0608857Y010204*
X0611251*
X0611298Y0102064*
X0611338Y0102077*
X0611352Y0102117*
X0611375Y0102164*
Y010218*
Y0102234*
Y0102288*
Y0102342*
Y0102396*
Y010245*
Y0102504*
Y0102558*
Y0102612*
Y0102666*
Y010272*
Y0102774*
Y0102828*
Y0102883*
Y0102937*
Y0102991*
Y0103045*
Y0103099*
Y0103153*
Y0103207*
Y0103261*
Y0103315*
Y0103369*
Y0103423*
Y0103477*
Y0103531*
Y0103585*
Y0103639*
Y0103693*
Y0103747*
Y0103802*
Y0103856*
Y010391*
Y0103964*
Y0104018*
Y0104033*
Y0104034*
X0611352Y0104081*
X0611345Y01041*
X0611344Y0104104*
X0611291Y0104107*
X061124Y0104117*
X061119Y0104134*
X0611143Y0104157*
Y0104158*
G37*
G36*
X062109Y0091399D02*
X0615005D01*
X0615004*
X0614957Y0091375*
X0614907Y0091359*
X0614856Y0091348*
X0614847*
X0614842Y0091344*
X0614795Y0091321*
X0614745Y0091304*
X0614694Y0091294*
X0614684*
X061468Y009129*
X0614633Y0091267*
X0614613Y0091261*
X0614601Y0091246*
X0614572Y0091221*
X0614546Y0091192*
X0614518Y0091167*
X0614492Y0091138*
X0614464Y0091113*
X0614438Y0091084*
X0614409Y0091059*
X0614384Y009103*
X0614356Y0091005*
X061433Y0090976*
X0614301Y0090951*
X0614276Y0090922*
X0614247Y0090896*
X0614222Y0090868*
X0614193Y0090842*
X0614187Y0090835*
X0614168Y0090813*
X0614139Y0090788*
X0614114Y0090759*
X0614085Y0090734*
X061406Y0090705*
X0614031Y009068*
X0614006Y0090651*
X0613977Y0090626*
X0613952Y0090597*
X0613923Y0090572*
X0613917Y0090565*
X0613898Y0090543*
X0613869Y0090518*
X0613844Y0090489*
X0613815Y0090464*
X061379Y0090435*
X0613761Y009041*
X0613735Y0090381*
X0613707Y0090356*
X0613682Y0090327*
X0613653Y0090302*
X0613627Y0090273*
X0613599Y0090248*
X0613573Y0090219*
X0613545Y0090194*
X0613519Y0090165*
X061349Y009014*
X0613465Y0090111*
X0613436Y0090086*
X0613411Y0090057*
X0613382Y0090031*
X0613357Y0090003*
X0613332Y0089981*
X0613328Y0089977*
X0613322Y008997*
X0613303Y0089949*
X0613274Y0089923*
X0613249Y0089894*
X0613234Y0089882*
X061323Y0089869*
X0613228Y0089862*
X0613205Y0089815*
X0613204*
Y0089799*
X0613201Y0089747*
X0613191Y0089696*
X0613174Y0089646*
X0613151Y0089599*
X061315*
Y0089583*
Y0089529*
Y0089475*
Y0089421*
Y0089367*
Y0089313*
Y0089259*
Y0089205*
Y0089151*
Y0089097*
Y0089043*
Y0088989*
Y0088934*
Y008888*
Y0088826*
Y0088772*
Y0088718*
Y0088664*
Y008861*
Y0088556*
Y0088502*
Y0088448*
Y0088394*
Y008834*
Y0088286*
Y0088232*
Y0088178*
Y0088124*
Y0088069*
Y0088016*
Y0087961*
Y0087907*
Y0087853*
Y0087799*
Y0087745*
Y0087691*
Y0087637*
Y0087583*
Y0087529*
Y0087475*
Y0087421*
Y0087367*
Y0087313*
Y0087259*
Y0087204*
Y0087151*
Y0087096*
Y0087042*
Y0086988*
Y0086934*
Y008688*
Y0086826*
Y0086772*
Y0086718*
Y0086664*
Y008661*
Y0086556*
Y0086502*
Y0086448*
Y0086394*
Y0086339*
Y0086286*
Y0086231*
Y0086177*
Y0086123*
Y0086069*
Y0086015*
Y0085961*
Y0085907*
Y0085853*
Y0085799*
Y0085745*
Y0085691*
Y0085637*
Y0085583*
Y0085529*
Y0085474*
Y0085421*
Y0085366*
Y0085312*
Y0085258*
Y0085204*
Y008515*
Y0085096*
Y0085042*
Y0084988*
Y0084934*
Y008488*
Y0084826*
Y0084772*
Y0084718*
Y0084664*
Y008461*
Y0084556*
Y0084501*
Y0084447*
Y0084393*
Y0084339*
Y0084285*
Y0084231*
Y0084177*
Y0084123*
Y0084069*
Y0084015*
Y0083961*
Y0083907*
Y0083853*
Y0083799*
Y0083745*
Y0083691*
Y0083636*
Y0083582*
Y0083528*
Y0083474*
Y008342*
Y0083366*
Y0083312*
Y0083258*
Y0083204*
Y008315*
Y0083096*
Y0083042*
Y0082988*
Y0082934*
Y008288*
Y0082825*
Y0082771*
Y0082717*
Y0082663*
Y0082609*
Y0082555*
Y0082501*
Y0082447*
Y0082393*
Y0082339*
Y0082285*
Y0082231*
Y0082177*
Y0082161*
X0613151*
X0613174Y0082114*
X0613191Y0082064*
X0613201Y0082013*
Y0082003*
X0613205Y0081999*
X0613228Y0081952*
X0613234Y0081932*
X0613249Y008192*
X0613274Y0081891*
X0613303Y0081866*
X0613328Y0081837*
X0613357Y0081811*
X0613382Y0081783*
X0613411Y0081757*
X0613436Y0081729*
X0613465Y0081703*
X0613484Y0081681*
X061349Y0081674*
X0613519Y0081649*
X0613545Y008162*
X0613557Y008161*
X0613573Y0081595*
X0613599Y0081566*
X0613627Y0081541*
X0613653Y0081512*
X0613671Y0081496*
X0613682Y0081487*
X0613707Y0081458*
X0613735Y0081433*
X0613761Y0081404*
X0613783Y0081385*
X061379Y0081379*
X0613815Y008135*
X0613844Y0081325*
X0613869Y0081296*
X0613898Y0081271*
X0613923Y0081242*
X0613952Y0081217*
X0613977Y0081188*
X0614006Y0081163*
X0614031Y0081134*
X061406Y0081109*
X0614079Y0081087*
X0614085Y008108*
X0614114Y0081055*
X0614139Y0081027*
Y0081026*
X0614153Y0081013*
X0614168Y0081001*
X0614193Y0080972*
X0614222Y0080946*
X0614247Y0080918*
X0614265Y0080902*
X0614276Y0080892*
X0614301Y0080864*
X061433Y0080838*
X0614356Y0080809*
X0614368Y0080799*
X0614384Y0080784*
X0614409Y0080756*
X0614438Y008073*
X0614464Y0080702*
X0614492Y0080676*
X0614518Y0080647*
X0614546Y0080622*
X0614572Y0080593*
X0614601Y0080568*
X0614626Y0080539*
X0614655Y0080514*
X0614668Y0080499*
X0614687Y0080493*
X0614734Y008047*
X0614739Y0080466*
X0614748*
X0614799Y0080456*
X0614849Y0080439*
X0614896Y0080415*
X0621323*
Y0080447*
Y0080501*
Y0080555*
Y0080609*
Y0080663*
Y0080717*
Y0080771*
Y0080825*
Y0080879*
Y0080933*
Y0080987*
Y0081042*
Y0081095*
Y008115*
Y0081204*
Y0081258*
Y0081312*
Y0081366*
Y008142*
Y0081474*
Y0081528*
Y0081582*
Y0081636*
Y008169*
Y0081744*
Y0081798*
Y0081852*
Y0081906*
Y008196*
Y0082015*
Y0082069*
Y0082123*
Y0082177*
Y0082231*
Y0082285*
Y0082339*
Y0082393*
Y0082447*
Y0082471*
X0621307Y0082478*
X0621306Y0082479*
X0615885*
X0615833Y0082482*
X0615781Y0082492*
X0615731Y0082509*
X0615685Y0082532*
X0615654Y0082553*
X0615623Y0082563*
X0615576Y0082586*
X0615533Y0082616*
X0615493Y008265*
X0615459Y008269*
X061543Y0082733*
X0615406Y008278*
X0615403Y008279*
X0615396Y008281*
X0615376Y0082841*
X0615352Y0082888*
X0615336Y0082938*
X0615325Y0082989*
X0615322Y0083042*
Y0083096*
Y008315*
Y0083204*
Y0083258*
Y0083312*
Y0083366*
Y008342*
Y0083474*
Y0083528*
Y0083582*
Y0083636*
Y0083691*
Y0083745*
Y0083799*
Y0083853*
Y0083907*
Y0083961*
Y0084015*
Y0084069*
Y0084123*
Y0084177*
Y0084231*
Y0084285*
Y0084339*
Y0084393*
Y0084447*
Y0084501*
Y0084556*
Y008461*
Y0084664*
Y0084718*
Y0084772*
Y0084826*
Y008488*
Y0084934*
Y0084988*
Y0085042*
Y0085096*
Y008515*
Y0085204*
Y0085258*
Y0085312*
Y0085366*
Y0085421*
Y0085474*
Y0085529*
Y0085583*
Y0085637*
Y0085691*
Y0085745*
Y0085799*
Y0085853*
Y0085907*
Y0085961*
Y0086015*
Y0086069*
Y0086123*
Y0086177*
Y0086231*
Y0086286*
Y0086339*
Y0086394*
Y0086448*
Y0086502*
Y0086556*
Y008661*
Y0086664*
Y0086718*
Y0086772*
Y0086826*
Y008688*
Y0086934*
Y0086988*
Y0087042*
Y0087096*
Y0087151*
Y0087204*
Y0087259*
Y0087313*
Y0087367*
Y0087421*
Y0087475*
Y0087529*
Y0087583*
Y0087637*
Y0087691*
Y0087745*
Y0087799*
Y0087853*
Y0087907*
Y0087961*
Y0088016*
Y0088069*
Y0088124*
Y0088178*
Y0088232*
Y0088286*
Y008834*
Y0088394*
Y0088448*
Y0088502*
Y0088556*
Y008861*
Y0088664*
Y0088718*
Y0088772*
X0615325Y0088825*
X0615336Y0088876*
X0615352Y0088926*
X0615376Y0088973*
X0615405Y0089016*
X0615439Y0089056*
X0615442Y0089058*
X0615468Y0089081*
X0615493Y008911*
X0615522Y0089135*
X0615547Y0089164*
X0615587Y0089198*
X061563Y0089228*
X0615677Y0089251*
X0615727Y0089268*
X0615778Y0089278*
X0615831Y0089281*
X0620982*
X0620983Y0089282*
X062103Y0089305*
X0621079Y0089322*
X0621131Y0089332*
X0621183Y0089335*
X0621237*
X0621289Y0089332*
X0621323Y0089325*
Y0089367*
Y0089421*
Y0089475*
Y0089529*
Y0089583*
Y0089637*
Y0089691*
Y0089745*
Y0089799*
Y0089854*
Y0089908*
Y0089962*
Y0090016*
Y009007*
Y0090124*
Y0090178*
Y0090232*
Y0090286*
Y009034*
Y0090394*
Y0090448*
Y0090502*
Y0090556*
Y009061*
Y0090664*
Y0090719*
Y0090773*
Y0090827*
Y0090881*
Y0090935*
Y0090989*
Y0091043*
Y0091097*
Y0091151*
Y0091205*
Y0091259*
Y0091313*
Y0091345*
X0621291*
X0621239Y0091348*
X0621187Y0091359*
X0621138Y0091375*
X0621091Y0091399*
X062109*
G37*
G36*
X0630713D02*
X0630376D01*
X0630362Y0091386*
X0630358Y0091383*
X0630333Y0091354*
X0630304Y0091329*
X0630278Y00913*
X063025Y0091275*
X0630224Y0091246*
X0630196Y0091221*
X063018Y0091203*
X063017Y0091192*
X0630142Y0091167*
X0630116Y0091138*
X0630088Y0091113*
X0630062Y0091084*
X0630033Y0091059*
X0630008Y009103*
X0629979Y0091005*
X0629954Y0090976*
X0629925Y0090951*
X06299Y0090922*
X0629871Y0090896*
X0629846Y0090868*
X0629817Y0090842*
X0629792Y0090813*
X0629763Y0090788*
X0629738Y0090759*
X0629709Y0090734*
X0629684Y0090705*
X0629655Y009068*
X062963Y0090651*
X0629601Y0090626*
X0629576Y0090597*
X0629551Y0090575*
X0629547Y0090572*
X0629522Y0090543*
X0629493Y0090518*
X0629487Y0090511*
X0629468Y0090489*
X0629439Y0090464*
X0629414Y0090435*
X0629385Y009041*
X0629359Y0090381*
X0629331Y0090356*
X0629305Y0090327*
X0629277Y0090302*
X0629251Y0090273*
X0629222Y0090248*
X0629197Y0090219*
X0629172Y0090197*
X0629169Y0090194*
X0629143Y0090165*
X0629114Y009014*
X0629089Y0090111*
X062906Y0090086*
X0629035Y0090057*
X062901Y0090035*
X0629006Y0090031*
X0628981Y0090003*
X0628956Y0089981*
X0628952Y0089977*
X0628946Y008997*
X0628927Y0089949*
X0628898Y0089923*
X0628873Y0089894*
X0628844Y0089869*
X0628819Y008984*
X062879Y0089815*
X0628765Y0089786*
X0628736Y0089761*
X0628711Y0089732*
X0628682Y0089707*
X0628657Y0089678*
X0628628Y0089653*
X0628613Y0089636*
X0628603Y0089624*
X0628574Y0089599*
X0628548Y008957*
X0628527Y0089552*
X0629995*
X0630047Y0089548*
X0630099Y0089538*
X0630149Y0089521*
X0630196Y0089498*
X0630239Y0089469*
X0630278Y0089434*
X0630313Y0089395*
X0630342Y0089351*
X0630365Y0089304*
X0630382Y0089254*
X0630393Y0089203*
X0630396Y0089151*
Y0089097*
Y0089043*
Y0088989*
Y0088934*
Y008888*
Y0088826*
Y0088772*
Y0088718*
Y0088664*
Y008861*
Y0088556*
Y0088502*
Y0088448*
Y0088394*
Y008834*
Y0088286*
Y0088232*
Y0088178*
Y0088124*
Y0088069*
Y0088016*
Y0087961*
Y0087907*
Y0087853*
Y0087799*
Y0087745*
Y0087691*
Y0087637*
Y0087583*
Y0087529*
Y0087475*
Y0087421*
Y0087367*
Y0087313*
Y0087259*
Y0087204*
Y0087151*
Y0087096*
Y0087042*
Y0086988*
Y0086934*
Y008688*
Y0086826*
Y0086772*
Y0086718*
Y0086664*
Y008661*
Y0086556*
Y0086502*
Y0086448*
Y0086394*
Y0086339*
Y0086286*
Y0086231*
Y0086177*
X0630393Y0086125*
X0630382Y0086074*
X0630365Y0086024*
X0630342Y0085977*
X0630313Y0085933*
X0630278Y0085894*
X0630239Y0085859*
X0630196Y008583*
X0630149Y0085807*
X0630099Y008579*
X0630047Y008578*
X0629995Y0085777*
X0626049*
X0625996Y008578*
X0625945Y008579*
X0625895Y0085807*
X0625848Y008583*
X0625805Y0085859*
X0625765Y0085894*
X0625731Y0085933*
X0625701Y0085977*
X0625678Y0086024*
X0625661Y0086074*
X0625651Y0086125*
X0625648Y0086177*
Y0086231*
Y0086286*
Y0086339*
Y0086394*
Y0086402*
X0625629Y008638*
X06256Y0086355*
X0625575Y0086326*
X0625546Y0086301*
X0625521Y0086272*
X0625496Y008625*
X0625492Y0086247*
X0625467Y0086218*
X0625438Y0086193*
X0625413Y0086164*
X0625384Y0086139*
X0625359Y008611*
X062533Y0086085*
X0625305Y0086056*
X0625276Y0086031*
X0625251Y0086002*
X0625222Y0085977*
X0625197Y0085948*
X0625168Y0085923*
X0625143Y0085894*
X0625114Y0085869*
X0625089Y008584*
X062506Y0085815*
X0625035Y0085786*
X0625006Y008576*
X062498Y0085732*
X0624952Y0085707*
X0624946Y00857*
X0624926Y0085678*
X0624898Y0085652*
X0624872Y0085624*
X0624844Y0085598*
X0624818Y008557*
X0624789Y0085544*
X0624764Y0085515*
X0624735Y008549*
X062471Y0085461*
X0624681Y0085436*
X0624656Y0085407*
X0624627Y0085382*
X0624602Y0085353*
X0624573Y0085328*
X0624548Y0085299*
X0624519Y0085274*
X0624494Y0085245*
X0624465Y008522*
X062444Y0085191*
X0624411Y0085166*
X0624386Y0085137*
X0624357Y0085112*
X0624343Y0085096*
X0624332Y0085083*
X0624303Y0085058*
X0624278Y0085029*
X0624249Y0085004*
X0624224Y0084975*
X0624195Y008495*
X0624169Y0084921*
X0624141Y0084895*
X0624131Y0084884*
X0624115Y0084867*
X0624087Y0084842*
X0624073Y0084826*
X0624061Y0084813*
X0624033Y0084787*
X0624007Y0084759*
X0623979Y0084733*
X0623953Y0084705*
X0623924Y0084679*
X0623899Y008465*
X062387Y0084625*
X0623845Y0084596*
X0623828Y0084582*
X0623816Y0084571*
X0623791Y0084542*
X0623752Y0084508*
X0623708Y0084479*
X0623661Y0084455*
X0623642Y0084449*
X0623629Y0084434*
X06236Y0084409*
X0623575Y008438*
X0623546Y0084355*
X0623521Y0084326*
X0623492Y0084301*
X0623488Y0084296*
X0623476Y0084283*
Y0084231*
Y0084177*
Y0084123*
Y0084069*
Y0084015*
Y0083961*
Y0083907*
Y0083853*
Y0083799*
Y0083745*
Y0083691*
Y0083636*
Y0083582*
Y0083528*
Y0083474*
Y008342*
Y0083366*
Y0083312*
Y0083258*
Y0083204*
Y008315*
Y0083096*
Y0083042*
Y0082988*
Y0082934*
Y008288*
Y0082825*
Y0082771*
Y0082717*
Y0082663*
Y0082609*
Y0082555*
Y0082501*
Y0082447*
Y0082393*
Y0082339*
Y0082285*
Y0082231*
Y0082177*
Y0082123*
Y0082069*
Y0082015*
Y008196*
Y0081906*
Y0081852*
Y0081798*
Y0081744*
Y008169*
Y0081636*
Y0081582*
Y0081528*
Y0081474*
Y008142*
Y0081366*
Y0081312*
Y0081258*
Y0081204*
Y008115*
Y0081095*
Y0081042*
Y0080987*
Y0080933*
Y0080879*
Y0080825*
Y0080771*
Y0080717*
Y0080663*
Y0080609*
Y0080555*
Y0080501*
Y0080447*
Y0080423*
X0623492Y0080415*
X0625631*
X0625632*
X0625642Y0080421*
X0625647Y0080431*
X0625648*
Y0080447*
Y0080501*
Y0080555*
Y0080609*
Y0080663*
Y0080717*
Y0080771*
Y0080825*
Y0080879*
Y0080933*
Y0080987*
Y0081042*
Y0081095*
Y008115*
Y0081204*
Y0081258*
Y0081312*
Y0081366*
Y008142*
Y0081474*
Y0081528*
Y0081582*
Y0081636*
Y008169*
Y0081744*
Y0081798*
Y0081852*
Y0081906*
Y008196*
Y0082015*
Y0082069*
Y0082123*
Y0082177*
Y0082231*
Y0082285*
Y0082339*
Y0082393*
Y0082447*
Y0082501*
Y0082555*
Y0082609*
Y0082663*
Y0082717*
Y0082771*
Y0082825*
Y008288*
Y0082934*
Y0082988*
Y0083042*
Y0083096*
Y008315*
Y0083204*
Y0083258*
Y0083312*
Y0083366*
Y008342*
Y0083474*
X0625651Y0083527*
X0625661Y0083578*
X0625678Y0083628*
X0625701Y0083675*
X0625722Y0083706*
X0625732Y0083736*
X0625756Y0083783*
X0625785Y0083826*
X0625819Y0083866*
X0625859Y00839*
X0625902Y008393*
X0625949Y0083953*
X0625968Y0083959*
X062598Y0083963*
X062601Y0083984*
X0626057Y0084007*
X0626107Y0084024*
X0626158Y0084034*
X0626211Y0084037*
X0629833*
X0629885Y0084034*
X0629937Y0084024*
X0629986Y0084007*
X0630033Y0083984*
X0630064Y0083963*
X0630094Y0083953*
X0630141Y008393*
X0630185Y00839*
X0630224Y0083866*
X0630259Y0083826*
X0630288Y0083783*
X0630311Y0083736*
X0630322Y0083706*
X0630342Y0083675*
X0630365Y0083628*
X0630382Y0083578*
X0630393Y0083527*
X0630396Y0083474*
Y008342*
Y0083366*
Y0083312*
Y0083258*
Y0083204*
Y008315*
Y0083096*
Y0083042*
Y0082988*
Y0082934*
Y008288*
Y0082825*
Y0082771*
Y0082717*
Y0082663*
Y0082609*
Y0082555*
Y0082501*
Y0082447*
Y0082393*
Y0082339*
Y0082285*
Y0082231*
Y0082177*
Y0082123*
Y0082069*
Y0082015*
Y008196*
Y0081906*
Y0081852*
Y0081798*
Y0081744*
Y008169*
Y0081636*
Y0081582*
Y0081528*
Y0081474*
Y008142*
Y0081366*
Y0081312*
Y0081258*
Y0081204*
Y008115*
Y0081095*
Y0081042*
Y0080987*
Y0080933*
Y0080879*
Y0080825*
Y0080771*
Y0080717*
Y0080663*
Y0080609*
Y0080555*
Y0080501*
Y0080447*
Y0080423*
X0630412Y0080415*
X0632551*
X0632552*
X0632562Y0080421*
X0632567Y0080431*
X0632568*
Y0080447*
Y0080501*
Y0080555*
Y0080609*
Y0080663*
Y0080717*
Y0080771*
Y0080825*
Y0080879*
Y0080933*
Y0080987*
Y0081042*
Y0081095*
Y008115*
Y0081204*
Y0081258*
Y0081312*
Y0081366*
Y008142*
Y0081474*
Y0081528*
Y0081582*
Y0081636*
Y008169*
Y0081744*
Y0081798*
Y0081852*
Y0081906*
Y008196*
Y0082015*
Y0082069*
Y0082123*
Y0082177*
Y0082231*
Y0082285*
Y0082339*
Y0082393*
Y0082447*
Y0082501*
Y0082555*
Y0082609*
Y0082663*
Y0082717*
Y0082771*
Y0082825*
Y008288*
Y0082934*
Y0082988*
Y0083042*
Y0083096*
Y008315*
Y0083204*
Y0083258*
Y0083312*
Y0083366*
Y008342*
Y0083474*
Y0083528*
Y0083582*
Y0083636*
Y0083691*
Y0083745*
Y0083799*
Y0083853*
Y0083907*
Y0083961*
Y0084015*
Y0084069*
Y0084123*
Y0084177*
Y0084231*
Y0084285*
Y0084339*
Y0084393*
Y0084447*
Y0084501*
Y0084556*
Y008461*
Y0084664*
Y0084718*
Y0084772*
Y0084826*
Y008488*
Y0084934*
Y0084988*
Y0085042*
Y0085096*
Y008515*
Y0085204*
Y0085258*
Y0085312*
Y0085366*
Y0085421*
Y0085474*
Y0085529*
Y0085583*
Y0085637*
Y0085691*
Y0085745*
Y0085799*
Y0085853*
Y0085907*
Y0085961*
Y0086015*
Y0086069*
Y0086123*
Y0086177*
Y0086231*
Y0086286*
Y0086339*
Y0086394*
Y0086448*
Y0086502*
Y0086556*
Y008661*
Y0086664*
Y0086718*
Y0086772*
Y0086826*
Y008688*
Y0086934*
Y0086988*
Y0087042*
Y0087096*
Y0087151*
Y0087204*
Y0087259*
Y0087313*
Y0087367*
Y0087421*
Y0087475*
Y0087529*
Y0087583*
Y0087637*
Y0087691*
Y0087745*
Y0087799*
Y0087853*
Y0087907*
Y0087961*
Y0088016*
Y0088069*
Y0088124*
Y0088178*
Y0088232*
Y0088286*
Y008834*
Y0088394*
Y0088448*
Y0088502*
Y0088556*
Y008861*
Y0088664*
Y0088718*
Y0088772*
Y0088826*
Y008888*
Y0088934*
Y0088989*
Y0089043*
Y0089097*
Y0089151*
Y0089205*
Y0089259*
Y0089313*
Y0089367*
Y0089421*
Y0089475*
Y0089529*
Y0089544*
X0632567Y0089545*
X0632544Y0089592*
X0632527Y0089642*
X0632517Y0089693*
X0632514Y0089745*
Y0089761*
X0632513*
X063249Y0089808*
X0632473Y0089858*
X0632465Y0089899*
X0632444Y0089923*
X0632415Y0089949*
X0632396Y008997*
X0632389Y0089977*
X0632361Y0090003*
X0632335Y0090031*
X0632307Y0090057*
X0632281Y0090086*
X0632253Y0090111*
X0632227Y009014*
X0632198Y0090165*
X0632173Y0090194*
X0632144Y0090219*
X0632119Y0090248*
X063209Y0090273*
X063208Y0090285*
X0632065Y0090302*
X0632036Y0090327*
X0632011Y0090356*
X0631982Y0090381*
X0631957Y009041*
X0631928Y0090435*
X0631903Y0090464*
X0631874Y0090489*
X0631849Y0090518*
X063182Y0090543*
X0631795Y0090572*
X0631766Y0090597*
X0631741Y0090626*
X0631712Y0090651*
X0631687Y009068*
X0631658Y0090705*
X0631633Y0090734*
X0631604Y0090759*
X0631578Y0090788*
X063155Y0090813*
X0631525Y0090842*
X0631496Y0090868*
X063147Y0090896*
X0631442Y0090922*
X0631416Y0090951*
X0631388Y0090976*
X0631362Y0091005*
X0631333Y009103*
X0631308Y0091059*
X0631279Y0091084*
X0631254Y0091113*
X0631225Y0091138*
X06312Y0091167*
X0631171Y0091192*
X0631146Y0091221*
X0631117Y0091246*
X0631104Y0091261*
X0631085Y0091267*
X0631038Y009129*
X0631007Y0091311*
X0630977Y0091321*
X063093Y0091344*
X0630929Y0091345*
X0630914*
X0630862Y0091348*
X063081Y0091359*
X0630761Y0091375*
X0630714Y0091399*
X0630713*
G37*
G36*
X0626983Y0110591D02*
X0626612D01*
Y0110559*
Y0110505*
Y0110451*
Y0110397*
Y0110343*
Y0110289*
Y0110235*
Y0110181*
Y0110127*
Y0110073*
Y0110019*
Y0109965*
Y0109911*
Y0109856*
Y0109802*
Y0109748*
Y0109694*
Y010964*
Y0109586*
Y0109532*
Y0109478*
Y0109424*
Y010937*
Y0109316*
Y0109262*
Y0109208*
Y0109154*
Y01091*
Y0109046*
Y0108992*
Y0108938*
Y0108883*
Y0108829*
Y0108775*
Y0108721*
Y0108667*
Y0108613*
Y0108559*
Y0108505*
Y0108451*
Y0108397*
Y0108343*
Y0108289*
Y0108235*
Y0108181*
Y0108126*
Y0108072*
Y0108018*
Y0107964*
Y010791*
Y0107856*
Y0107802*
Y0107748*
Y0107694*
Y010764*
Y0107586*
Y0107532*
Y0107478*
Y0107424*
Y010737*
Y0107316*
Y0107262*
Y0107208*
Y0107153*
Y0107099*
Y0107045*
Y0106991*
Y0106937*
Y0106883*
Y0106829*
Y0106775*
Y0106721*
Y0106667*
Y0106613*
Y0106559*
Y0106505*
Y0106451*
Y0106397*
Y0106342*
Y0106288*
Y0106234*
Y010618*
Y0106126*
Y0106072*
Y0106018*
Y0105964*
Y010591*
Y0105856*
Y0105802*
Y0105748*
Y0105694*
Y010564*
Y0105586*
Y0105532*
Y0105477*
Y0105423*
Y0105369*
Y0105315*
Y0105261*
Y0105207*
Y0105153*
Y0105099*
Y0105045*
Y0104991*
Y0104937*
Y0104883*
Y0104829*
Y0104775*
Y0104721*
Y0104667*
Y0104613*
Y0104558*
Y0104504*
Y010445*
Y0104396*
Y0104342*
Y0104288*
Y0104234*
Y010418*
Y0104126*
Y0104072*
Y0104018*
Y0103964*
Y010391*
Y0103856*
Y0103802*
Y0103747*
Y0103693*
Y0103639*
Y0103585*
Y0103531*
Y0103477*
Y0103423*
Y0103369*
Y0103315*
Y0103261*
Y0103207*
Y0103153*
Y0103099*
Y0103045*
Y0102991*
Y0102937*
Y0102883*
Y0102828*
Y0102774*
Y010272*
Y0102666*
Y0102612*
Y0102558*
Y0102504*
Y010245*
Y0102396*
Y0102342*
Y0102288*
Y0102234*
Y010218*
Y0102126*
Y0102072*
Y0102017*
Y0101963*
Y0101909*
Y0101855*
Y0101801*
Y0101747*
Y0101693*
Y0101639*
Y0101585*
Y0101531*
Y0101477*
Y0101423*
Y0101369*
Y0101315*
Y0101261*
Y0101207*
Y0101153*
Y0101099*
Y0101044*
Y010099*
Y0100936*
Y0100882*
Y0100828*
Y0100774*
Y010072*
Y0100666*
Y0100612*
Y0100558*
Y0100504*
Y010045*
Y0100396*
Y0100342*
Y0100287*
Y0100233*
Y0100179*
Y0100125*
Y0100071*
Y0100017*
Y0099963*
Y0099909*
Y0099855*
Y0099801*
Y0099747*
Y0099693*
Y0099639*
Y0099585*
Y0099531*
Y0099477*
Y0099423*
Y0099369*
Y0099314*
Y009926*
Y0099206*
Y0099152*
Y0099098*
Y0099044*
Y009899*
Y0098936*
Y0098882*
Y0098828*
Y0098774*
Y009872*
Y0098666*
Y0098612*
Y0098558*
Y0098504*
Y0098449*
Y0098395*
Y0098341*
Y0098287*
Y0098233*
Y0098179*
Y0098125*
Y0098071*
Y0098017*
Y0097963*
Y0097909*
Y0097855*
Y0097801*
Y0097747*
Y0097693*
Y0097638*
Y0097584*
Y009753*
Y0097476*
Y0097422*
Y0097368*
Y0097314*
Y009726*
Y0097206*
Y0097152*
Y0097098*
Y0097044*
Y009699*
Y0096936*
Y0096882*
Y0096828*
Y0096773*
Y0096719*
Y0096665*
Y0096611*
Y0096557*
Y0096503*
Y0096449*
Y0096395*
Y0096341*
Y0096287*
Y0096233*
Y0096179*
Y0096125*
Y0096071*
Y0096017*
Y0095963*
Y0095908*
Y0095854*
Y00958*
Y0095746*
Y0095692*
Y0095638*
Y0095584*
Y009553*
Y0095476*
Y0095422*
Y0095368*
Y0095314*
Y009526*
Y0095206*
Y0095152*
Y0095098*
Y0095043*
Y009499*
Y0094935*
Y0094881*
Y0094827*
Y0094773*
Y0094719*
Y0094665*
Y0094611*
Y0094557*
Y0094503*
Y0094449*
Y0094395*
Y0094341*
Y0094287*
Y0094233*
Y0094178*
Y0094125*
Y009407*
Y0094016*
Y0093962*
Y0093908*
Y0093854*
Y00938*
Y0093746*
Y0093692*
Y0093638*
Y0093584*
Y009353*
Y0093476*
Y0093422*
Y0093368*
Y0093313*
Y009326*
Y0093205*
Y0093151*
Y0093097*
X0626608Y0093045*
X0626598Y0092993*
X0626581Y0092944*
X0626558Y0092897*
X0626529Y0092853*
X0626494Y0092814*
X0626465Y0092789*
X062644Y009276*
X0626411Y0092734*
X0626386Y0092706*
X0626357Y0092681*
X0626332Y0092652*
X0626303Y0092626*
X0626278Y0092598*
X0626249Y0092572*
X0626224Y0092544*
X0626195Y0092518*
X062617Y0092489*
X0626145Y0092467*
X0626141Y0092464*
X0626116Y0092435*
X0626087Y009241*
X062608Y0092403*
X0626062Y0092381*
X0626033Y0092356*
X0626008Y0092327*
X0625979Y0092302*
X0625953Y0092273*
X0625925Y0092248*
X0625905Y0092226*
X06259Y0092219*
X0625875Y0092197*
X0625871Y0092194*
X0625845Y0092165*
X0625821Y0092144*
X0625817Y009214*
X0625791Y0092111*
X0625763Y0092086*
X0625737Y0092057*
X0625708Y0092032*
X0625683Y0092003*
X0625654Y0091978*
X0625629Y0091949*
X06256Y0091924*
X0625575Y0091895*
X0625536Y009186*
X0625492Y0091831*
X0625445Y0091808*
X0625426Y0091801*
X0625413Y0091787*
X0625384Y0091761*
X0625359Y0091733*
X062533Y0091707*
X0625305Y0091679*
X0625276Y0091653*
X0625251Y0091624*
X0625222Y0091599*
X0625197Y009157*
X0625168Y0091545*
X0625143Y0091516*
X0625114Y0091491*
X06251Y0091475*
X0625089Y0091462*
X062506Y0091437*
X062504Y0091415*
X0625035Y0091408*
X0625008Y0091385*
X0625006Y0091383*
X062498Y0091354*
X0624952Y0091329*
X0624926Y00913*
X0624898Y0091275*
X0624872Y0091246*
X0624844Y0091221*
X0624818Y0091192*
X0624789Y0091167*
X0624764Y0091138*
X0624735Y0091113*
X062471Y0091084*
X0624681Y0091059*
X0624671Y0091047*
X0624656Y009103*
X0624627Y0091005*
X0624602Y0090976*
X0624573Y0090951*
X0624548Y0090922*
X0624519Y0090896*
X0624494Y0090868*
X0624465Y0090842*
X0624459Y0090835*
X062444Y0090813*
X0624411Y0090788*
X0624409Y0090786*
X0624386Y0090759*
X0624357Y0090734*
X0624332Y0090705*
X0624303Y009068*
X0624278Y0090651*
X0624249Y0090626*
X0624224Y0090597*
X0624199Y0090575*
X0624195Y0090572*
X0624169Y0090543*
X0624141Y0090518*
X0624115Y0090489*
X0624087Y0090464*
X0624072Y0090447*
X0624061Y0090435*
X0624033Y009041*
X0624007Y0090381*
X0623979Y0090356*
X0623953Y0090327*
X0623936Y0090312*
X0623924Y0090302*
X0623909Y0090285*
X0623899Y0090273*
X062387Y0090248*
X0623845Y0090219*
X0623828Y0090204*
X0623816Y0090194*
X0623791Y0090165*
X0623762Y009014*
X0623737Y0090111*
X0623708Y0090086*
X0623683Y0090057*
X0623658Y0090035*
X0623654Y0090031*
X0623629Y0090003*
X06236Y0089977*
X0623575Y0089949*
X0623546Y0089923*
X0623521Y0089894*
X0623492Y0089869*
X0623473Y0089847*
X0623467Y008984*
X0623438Y0089815*
X0623413Y0089786*
X0623384Y0089761*
X0623359Y0089732*
X0623338Y0089714*
X062333Y0089707*
X0623324Y00897*
X0623305Y0089678*
X0623276Y0089653*
X062325Y0089624*
X0623222Y0089599*
X0623196Y008957*
X0623168Y0089545*
X0623142Y0089516*
X0623113Y0089491*
X0623088Y0089462*
X0623059Y0089437*
X0623034Y0089408*
X0623005Y0089383*
X062298Y0089354*
X0622951Y0089329*
X0622926Y00893*
X0622897Y0089275*
X0622872Y0089246*
X0622847Y0089224*
X0622843Y008922*
X0622818Y0089192*
X0622789Y0089166*
X0622764Y0089138*
X0622735Y0089112*
X062271Y0089084*
X0622681Y0089058*
X0622656Y008903*
X0622627Y0089004*
X0622602Y0088975*
X0622573Y008895*
X0622548Y0088921*
X0622523Y0088899*
X0622519Y0088896*
X0622494Y0088867*
X0622465Y0088842*
X0622439Y0088813*
X0622411Y0088788*
X0622386Y0088759*
X0622357Y0088734*
X0622331Y0088705*
X0622303Y008868*
X0622277Y0088651*
X0622249Y0088626*
X0622223Y0088597*
X0622194Y0088572*
X0622175Y008855*
X0622169Y0088543*
X062214Y0088518*
X0622115Y0088489*
X0622086Y0088464*
X0622061Y0088435*
X0622032Y008841*
X0622007Y0088381*
X0621978Y0088355*
X0621953Y0088327*
X0621924Y0088301*
X0621899Y0088273*
X062186Y0088238*
X0621816Y0088209*
X0621769Y0088186*
X062175Y0088179*
X0621737Y0088165*
X0621708Y0088139*
X0621683Y0088111*
X0621654Y0088085*
X0621629Y0088056*
X06216Y0088031*
X0621574Y0088002*
X0621546Y0087977*
X0621521Y0087948*
X0621492Y0087923*
X0621466Y0087894*
X0621438Y0087869*
X0621412Y008784*
X0621396Y0087826*
X0621383Y0087815*
X0621358Y0087786*
X0621329Y0087761*
X0621304Y0087732*
X0621275Y0087707*
X062125Y0087678*
X0621221Y0087653*
X0621196Y0087624*
X0621167Y0087599*
X0621142Y008757*
X0621113Y0087545*
X062109Y0087518*
X0621088Y0087516*
X0621059Y008749*
X0621034Y0087462*
X0621019Y0087449*
X0621013Y008743*
X062099Y0087383*
X062096Y0087339*
X0620926Y00873*
X0620911Y0087287*
X0620909Y0087281*
X0620905Y0087267*
X0620881Y008722*
X0620861Y008719*
X0620851Y0087159*
X0620827Y0087112*
Y0087096*
Y0087042*
Y0086988*
Y0086934*
Y008688*
Y0086826*
Y0086772*
Y0086718*
Y0086664*
Y008661*
Y0086556*
Y0086502*
Y0086448*
Y0086394*
Y0086339*
Y0086286*
Y0086231*
Y0086177*
Y0086123*
Y0086069*
Y0086015*
Y0085961*
Y0085907*
Y0085853*
Y0085799*
Y0085745*
Y0085691*
Y0085637*
Y0085583*
Y0085529*
Y0085474*
Y0085421*
Y0085366*
Y0085312*
Y0085258*
Y0085204*
Y008515*
Y0085099*
X0620852Y008507*
X0620881Y0085026*
X0620905Y0084979*
X0620911Y008496*
X0620923Y008495*
X0620926Y0084947*
X062096Y0084908*
X062099Y0084864*
X0621013Y0084817*
X0621019Y0084798*
X0621034Y0084785*
X0621059Y0084756*
X0621088Y0084731*
X0621113Y0084702*
X0621142Y0084677*
X0621167Y0084648*
X0621183Y0084634*
X0621199Y0084648*
X0621224Y0084677*
X0621253Y0084702*
X0621278Y0084731*
X0621288Y008474*
X0621307Y0084756*
X0621332Y0084785*
X0621335Y0084788*
X0621361Y008481*
X0621386Y0084839*
X0621415Y0084864*
X062144Y0084893*
X0621443Y0084895*
X0621469Y0084918*
X0621494Y0084947*
X0621523Y0084972*
X0621548Y0085001*
X0621577Y0085026*
X0621602Y0085055*
X0621631Y008508*
X0621656Y0085109*
X0621685Y0085135*
X062171Y0085163*
X0621739Y0085189*
X0621765Y0085217*
X0621793Y0085243*
X0621819Y0085271*
X062183Y0085281*
X0621847Y0085297*
X0621873Y0085325*
X0621901Y0085351*
X0621927Y008538*
X0621955Y0085405*
X0621981Y0085434*
X062201Y0085459*
X0622016Y0085466*
X0622035Y0085488*
X0622064Y0085513*
X0622089Y0085542*
X06221Y0085551*
X0622118Y0085567*
X0622143Y0085596*
X0622154Y0085605*
X0622172Y0085621*
X0622197Y008565*
X0622236Y0085684*
X062228Y0085714*
X0622327Y0085737*
X0622346Y0085743*
X0622359Y0085758*
X062237Y0085768*
X0622388Y0085783*
X0622413Y0085812*
X0622442Y0085837*
X0622467Y0085866*
X0622496Y0085891*
X0622521Y008592*
X062255Y0085945*
X0622575Y0085974*
X0622604Y0086*
X0622629Y0086028*
X0622658Y0086054*
X0622684Y0086082*
X0622686Y0086085*
X0622712Y0086108*
X0622738Y0086136*
X0622749Y0086146*
X0622766Y0086162*
X0622792Y008619*
X062282Y0086216*
X0622846Y0086245*
X0622874Y008627*
X06229Y0086299*
X0622929Y0086324*
X0622954Y0086353*
X0622965Y0086362*
X0622983Y0086378*
X0623008Y0086407*
X0623037Y0086432*
X0623062Y0086461*
X0623091Y0086486*
X0623116Y0086515*
X0623145Y008654*
X062317Y0086569*
X0623181Y0086579*
X0623199Y0086594*
X0623224Y0086623*
X0623253Y0086648*
X0623278Y0086677*
X0623289Y0086687*
X0623307Y0086702*
X0623332Y0086731*
X0623335Y0086734*
X0623361Y0086756*
X0623386Y0086785*
X0623415Y008681*
X062344Y0086839*
X0623469Y0086865*
X0623494Y0086893*
X0623523Y0086919*
X0623549Y0086947*
X0623552Y008695*
X0623577Y0086973*
X0623603Y0087001*
X0623623Y008702*
X0623631Y0087027*
X0623657Y0087055*
X0623686Y0087081*
X0623711Y008711*
X0623722Y0087119*
X0623739Y0087135*
X0623765Y0087164*
X0623794Y0087189*
X0623819Y0087218*
X0623848Y0087243*
X0623873Y0087272*
X0623876Y0087274*
X0623902Y0087297*
X0623927Y0087326*
X0623956Y0087351*
X0623981Y008738*
X0623992Y0087389*
X062401Y0087405*
X0624035Y0087434*
X0624038Y0087437*
X0624064Y0087459*
X0624089Y0087488*
X0624092Y0087491*
X0624118Y0087513*
X0624143Y0087542*
X0624172Y0087567*
X0624197Y0087596*
X0624208Y0087605*
X0624226Y0087621*
X0624251Y008765*
X0624254Y0087653*
X062428Y0087675*
X0624305Y0087704*
X0624334Y008773*
X062436Y0087758*
X0624374Y0087771*
X0624388Y0087784*
X0624413Y0087812*
X0624442Y0087838*
X0624468Y0087866*
X0624471Y0087869*
X0624496Y0087892*
X0624522Y008792*
X062455Y0087946*
X0624576Y0087975*
X0624579Y0087977*
X0624605Y0088*
X0624606Y0088002*
X062463Y0088029*
X0624659Y0088054*
X0624684Y0088083*
X0624713Y0088108*
X0624738Y0088137*
X0624749Y0088146*
X0624767Y0088162*
X0624792Y0088191*
X0624821Y0088216*
X0624846Y0088245*
X0624857Y0088254*
X0624875Y008827*
X06249Y0088299*
X0624929Y0088324*
X0624954Y0088353*
X0624957Y0088356*
X0624983Y0088378*
X0625008Y0088407*
X0625037Y0088432*
X0625062Y0088461*
X0625091Y0088486*
X0625116Y0088515*
X0625145Y0088541*
X062517Y0088569*
X0625181Y0088578*
X0625199Y0088594*
X0625224Y0088623*
X0625253Y0088649*
X0625279Y0088677*
X0625307Y0088703*
X0625333Y0088731*
X0625361Y0088757*
X0625387Y0088785*
X0625416Y0088811*
X0625441Y008884*
X0625469Y0088865*
X0625495Y0088894*
X0625506Y0088903*
X0625524Y0088919*
X0625549Y0088948*
X0625559Y0088957*
X0625578Y0088973*
X0625603Y0089002*
X0625632Y0089027*
X0625657Y0089056*
X0625686Y0089081*
X0625711Y008911*
X062574Y0089135*
X0625765Y0089164*
X062578Y0089177*
X0625794Y0089189*
X06258Y0089196*
X0625819Y0089218*
X062584Y0089236*
X0625848Y0089243*
X0625873Y0089272*
X0625884Y0089282*
X0625902Y0089297*
X0625927Y0089326*
X0625956Y0089351*
X0625981Y008938*
X062601Y0089405*
X0626035Y0089434*
X0626064Y008946*
X0626089Y0089488*
X0626105Y0089502*
X0626118Y0089513*
X0626144Y0089542*
X0626155Y0089552*
X0626172Y0089568*
X0626198Y0089596*
X0626226Y0089622*
X0626252Y008965*
X062628Y0089676*
X0626306Y0089705*
X0626334Y008973*
X062636Y0089759*
X0626389Y0089784*
X0626414Y0089813*
X0626443Y0089838*
X0626468Y0089867*
X0626497Y0089892*
X0626522Y0089921*
X0626551Y0089946*
X0626576Y0089975*
X0626587Y0089985*
X0626605Y009*
X0626611Y0090007*
X062663Y0090029*
X0626659Y0090054*
X0626684Y0090083*
X0626695Y0090093*
X0626713Y0090108*
X0626738Y0090137*
X0626741Y009014*
X0626767Y0090162*
X0626792Y0090191*
X0626832Y0090226*
X0626875Y0090255*
X0626922Y0090278*
X0626933Y0090282*
X0626942Y0090285*
X0626954Y0090299*
X0626969Y0090312*
X0626983Y0090324*
X0627008Y0090353*
X0627037Y0090379*
X0627063Y0090407*
X0627091Y0090433*
X0627117Y0090461*
X0627145Y0090487*
X0627171Y0090516*
X0627182Y0090525*
X06272Y0090541*
X0627225Y009057*
X0627254Y0090595*
X0627279Y0090624*
X0627282Y0090626*
X0627308Y0090649*
X0627333Y0090678*
X0627336Y009068*
X0627362Y0090703*
X0627387Y0090732*
X0627402Y0090745*
X0627416Y0090757*
X0627441Y0090786*
X0627452Y0090795*
X062747Y0090811*
X0627495Y009084*
X0627506Y009085*
X0627524Y0090865*
X0627549Y0090894*
X0627578Y0090919*
X0627603Y0090948*
X0627632Y0090973*
X0627657Y0091002*
X0627686Y0091027*
X0627711Y0091056*
X0627722Y0091066*
X062774Y0091081*
X0627746Y0091088*
X0627765Y009111*
X0627794Y0091135*
X0627819Y0091164*
X0627848Y0091189*
X0627874Y0091218*
X0627877Y0091221*
X0627902Y0091243*
X0627928Y0091272*
X0627956Y0091298*
X0627982Y0091326*
X062801Y0091352*
X0628036Y009138*
X0628047Y009139*
X0628064Y0091406*
X062809Y0091435*
X0628119Y009146*
X0628144Y0091489*
X0628173Y0091514*
X0628198Y0091543*
X0628227Y0091568*
X0628252Y0091597*
X0628263Y0091606*
X0628281Y0091622*
X0628306Y0091651*
X0628317Y009166*
X0628335Y0091676*
X062836Y0091705*
X0628363Y0091707*
X0628389Y009173*
X0628414Y0091759*
X0628429Y0091772*
X0628435Y0091791*
X0628459Y0091838*
X0628488Y0091882*
X0628522Y0091921*
X0628537Y0091934*
X0628541Y0091946*
X0628544Y0091953*
X0628567Y0092*
X0628572Y0092008*
X0628587Y0092031*
X0628597Y0092061*
X0628621Y0092108*
X0628641Y0092139*
X0628652Y0092169*
X0628675Y0092216*
Y0092217*
Y0092232*
X0628679Y0092285*
X0628689Y0092336*
X0628706Y0092386*
X0628729Y0092433*
Y0092449*
Y0092503*
Y0092557*
Y0092611*
Y0092665*
Y0092719*
Y0092773*
Y0092827*
Y0092881*
Y0092935*
Y0092989*
Y0093043*
Y0093097*
Y0093151*
Y0093205*
Y009326*
Y0093313*
Y0093368*
Y0093422*
Y0093476*
Y009353*
Y0093584*
Y0093638*
Y0093692*
Y0093746*
Y00938*
Y0093854*
Y0093908*
Y0093962*
Y0094016*
Y009407*
Y0094125*
Y0094178*
Y0094233*
Y0094287*
Y0094341*
Y0094395*
Y0094449*
Y0094503*
Y0094557*
Y0094611*
Y0094665*
Y0094719*
Y0094773*
Y0094827*
Y0094881*
Y0094935*
Y009499*
Y0095043*
Y0095098*
Y0095152*
Y0095206*
Y009526*
Y0095314*
Y0095368*
Y0095422*
Y0095476*
Y009553*
Y0095584*
Y0095638*
Y0095692*
Y0095746*
Y00958*
Y0095854*
Y0095908*
Y0095963*
Y0096017*
Y0096071*
Y0096125*
Y0096179*
Y0096233*
Y0096287*
Y0096341*
Y0096395*
Y0096449*
Y0096503*
Y0096557*
Y0096611*
Y0096665*
Y0096719*
Y0096773*
Y0096828*
Y0096882*
Y0096936*
Y009699*
Y0097044*
Y0097098*
Y0097152*
Y0097206*
Y009726*
Y0097314*
Y0097368*
Y0097422*
Y0097476*
Y009753*
Y0097584*
Y0097638*
Y0097693*
Y0097747*
Y0097801*
Y0097855*
Y0097909*
Y0097963*
Y0098017*
Y0098071*
Y0098125*
Y0098179*
Y0098233*
Y0098287*
Y0098341*
Y0098395*
Y0098449*
Y0098504*
Y0098558*
Y0098612*
Y0098666*
Y009872*
Y0098774*
Y0098828*
Y0098882*
Y0098936*
Y009899*
Y0099044*
Y0099098*
Y0099152*
Y0099206*
Y009926*
Y0099314*
Y0099369*
Y0099423*
Y0099477*
Y0099531*
Y0099585*
Y0099639*
Y0099693*
Y0099747*
Y0099801*
Y0099855*
Y0099909*
Y0099963*
Y0100017*
Y0100071*
Y0100125*
Y0100179*
Y0100233*
Y0100287*
Y0100342*
Y0100396*
Y010045*
Y0100504*
Y0100558*
Y0100612*
Y0100666*
Y010072*
Y0100774*
Y0100828*
Y0100882*
Y0100936*
Y010099*
Y0101044*
Y0101099*
Y0101153*
Y0101207*
Y0101261*
Y0101315*
Y0101369*
Y0101423*
Y0101477*
Y0101531*
Y0101585*
Y0101639*
Y0101693*
Y0101747*
Y0101801*
Y0101855*
Y0101909*
Y0101963*
Y0102017*
Y0102072*
Y0102126*
Y010218*
Y0102234*
Y0102288*
Y0102342*
Y0102396*
Y010245*
Y0102504*
Y0102558*
Y0102612*
Y0102666*
Y010272*
Y0102774*
Y0102828*
Y0102883*
Y0102937*
Y0102991*
Y0103045*
Y0103099*
Y0103153*
Y0103207*
Y0103261*
Y0103315*
Y0103369*
Y0103423*
Y0103477*
Y0103531*
Y0103585*
Y0103639*
Y0103693*
Y0103747*
Y0103802*
Y0103856*
Y010391*
Y0103964*
Y0104018*
Y0104072*
Y0104126*
Y010418*
Y0104234*
Y0104288*
Y0104342*
Y0104396*
Y010445*
Y0104504*
Y0104558*
Y0104613*
Y0104667*
Y0104721*
Y0104775*
Y0104829*
Y0104883*
Y0104937*
Y0104991*
Y0105045*
Y0105099*
Y0105153*
Y0105207*
Y0105261*
Y0105315*
Y0105369*
Y0105423*
Y0105477*
Y0105532*
Y0105586*
Y010564*
Y0105694*
Y0105748*
Y0105802*
Y0105856*
Y010591*
Y0105964*
Y0106018*
Y0106072*
Y0106126*
Y010618*
Y0106234*
Y0106288*
Y0106342*
Y0106397*
Y0106451*
Y0106505*
Y0106559*
Y0106613*
Y0106667*
Y0106721*
Y0106775*
Y0106829*
Y0106883*
Y0106937*
Y0106991*
Y0107045*
Y0107099*
Y0107153*
Y0107208*
Y0107262*
Y0107316*
Y010737*
Y0107424*
Y0107478*
Y0107532*
Y0107586*
Y010764*
Y0107694*
Y0107748*
Y0107802*
Y0107856*
Y010791*
Y0107964*
Y0108018*
Y0108072*
Y0108126*
Y0108181*
Y0108235*
Y0108289*
Y0108343*
Y0108397*
Y0108451*
Y0108505*
Y0108559*
Y0108613*
Y0108667*
Y0108721*
Y0108775*
Y0108829*
Y0108845*
X0628706Y0108892*
X0628689Y0108942*
X0628679Y0108993*
X0628675Y0109046*
Y0109061*
X0628652Y0109108*
X0628645Y0109128*
X062863Y0109141*
X0628605Y0109169*
X0628576Y0109195*
X0628559Y0109214*
X0628551Y0109223*
X0628522Y0109249*
X0628497Y0109277*
X0628468Y0109303*
X0628458Y0109314*
X0628443Y0109332*
X0628414Y0109357*
X0628389Y0109386*
X062836Y0109411*
X0628335Y010944*
X0628306Y0109465*
X0628281Y0109494*
X0628252Y0109519*
X0628227Y0109548*
X0628198Y0109573*
X0628173Y0109602*
X0628144Y0109627*
X0628125Y0109649*
X0628119Y0109656*
X062809Y0109681*
X0628064Y010971*
X0628036Y0109735*
X062801Y0109764*
X0627982Y0109789*
X0627956Y0109818*
X0627928Y0109843*
X0627914Y0109858*
X0627902Y0109872*
X0627874Y0109897*
X0627864Y0109908*
X0627848Y0109926*
X0627819Y0109951*
X0627794Y010998*
X0627765Y0110006*
X062775Y0110023*
X062774Y0110034*
X0627711Y011006*
X0627686Y0110089*
X0627657Y0110114*
X0627632Y0110143*
X0627603Y0110168*
X0627578Y0110196*
X0627549Y0110222*
X0627524Y0110251*
X0627495Y0110276*
X062747Y0110305*
X0627441Y011033*
X0627416Y0110359*
X0627387Y0110384*
X0627377Y0110395*
X0627362Y0110413*
X0627333Y0110438*
X0627323Y011045*
X0627308Y0110467*
X0627279Y0110492*
X0627271Y0110501*
X0627266Y0110507*
X0627247Y0110513*
X06272Y0110537*
X0627199*
X0627184*
X0627132Y011054*
X062708Y0110551*
X062703Y0110567*
X0626983Y0110591*
G37*
G36*
X0653149Y0091399D02*
X064609D01*
X0646043Y0091375*
X0646023Y0091369*
X064602Y0091365*
Y0091313*
Y0091259*
Y0091205*
Y0091151*
Y0091097*
Y0091043*
Y0090989*
Y0090935*
Y0090881*
Y0090827*
Y0090773*
Y0090719*
Y0090664*
Y009061*
Y0090556*
Y0090502*
Y0090448*
Y0090394*
Y009034*
Y0090286*
Y0090232*
Y0090178*
Y0090124*
Y009007*
Y0090016*
Y0089962*
Y0089908*
Y0089854*
Y0089799*
Y0089745*
Y0089691*
Y0089637*
Y0089583*
Y0089529*
Y0089475*
Y0089421*
Y0089367*
Y0089313*
Y0089259*
Y0089205*
Y0089151*
Y0089097*
Y0089043*
Y0088989*
Y0088934*
Y008888*
Y0088826*
Y0088772*
Y0088718*
Y0088664*
Y008861*
Y0088556*
Y0088502*
Y0088448*
Y0088394*
Y008834*
Y0088286*
Y0088232*
Y0088178*
Y0088124*
Y0088069*
Y0088016*
Y0087961*
Y0087907*
Y0087853*
Y0087799*
Y0087745*
Y0087691*
Y0087637*
Y0087583*
Y0087529*
Y0087475*
Y0087421*
Y0087367*
Y0087313*
Y0087259*
Y0087204*
Y0087151*
Y0087096*
Y0087042*
Y0086988*
Y0086934*
Y008688*
Y0086826*
Y0086772*
Y0086718*
Y0086664*
Y008661*
Y0086556*
Y0086502*
Y0086448*
Y0086394*
Y0086339*
Y0086286*
Y0086231*
Y0086177*
Y0086123*
Y0086069*
Y0086015*
Y0085961*
Y0085907*
Y0085853*
Y0085799*
Y0085745*
Y0085691*
Y0085637*
Y0085583*
Y0085529*
Y0085474*
Y0085421*
Y0085366*
Y0085312*
Y0085258*
Y0085204*
Y008515*
Y0085096*
Y0085042*
Y0084988*
Y0084934*
Y008488*
Y0084826*
Y0084772*
Y0084718*
Y0084664*
Y008461*
Y0084556*
Y0084501*
Y0084447*
Y0084393*
Y0084339*
Y0084285*
Y0084231*
Y0084177*
Y0084123*
Y0084069*
Y0084015*
Y0083961*
Y0083907*
Y0083853*
Y0083799*
Y0083745*
Y0083691*
Y0083636*
Y0083582*
Y0083528*
Y0083474*
Y008342*
Y0083366*
Y0083312*
Y0083258*
Y0083204*
Y008315*
Y0083096*
Y0083042*
Y0082988*
Y0082934*
Y008288*
Y0082825*
Y0082771*
Y0082717*
Y0082663*
Y0082609*
Y0082555*
Y0082501*
Y0082447*
Y0082393*
Y0082339*
Y0082285*
Y0082231*
Y0082177*
Y0082123*
Y0082069*
Y0082015*
Y008196*
Y0081906*
Y0081852*
Y0081798*
Y0081744*
Y008169*
Y0081636*
Y0081582*
Y0081528*
Y0081474*
Y008142*
Y0081366*
Y0081312*
Y0081258*
Y0081204*
Y008115*
Y0081095*
Y0081042*
Y0080987*
Y0080933*
Y0080879*
Y0080825*
Y0080771*
Y0080717*
Y0080663*
Y0080609*
Y0080555*
Y0080501*
Y0080447*
Y0080415*
X0653311*
X0653312*
X0653359Y0080439*
X0653408Y0080456*
X065346Y0080466*
X0653512Y0080469*
X0653527*
X0653528Y008047*
X0653575Y0080493*
X0653594Y0080499*
X0653607Y0080514*
X0653636Y0080539*
X0653661Y0080568*
X0653664Y0080571*
X065369Y0080593*
X0653696Y00806*
X0653715Y0080622*
X0653744Y0080647*
X0653769Y0080676*
X065378Y0080686*
X0653798Y0080701*
X0653823Y008073*
X0653852Y0080756*
X0653877Y0080784*
X065388Y0080787*
X0653906Y008081*
X0653931Y0080838*
X0653942Y0080848*
X065396Y0080864*
X0653966Y008087*
X0653986Y0080892*
X0654014Y0080918*
X0654039Y0080946*
X0654068Y0080972*
X0654094Y0081001*
X0654122Y0081026*
X0654123Y0081027*
X0654148Y0081055*
X0654177Y008108*
X0654202Y0081109*
X065423Y0081134*
X0654237Y0081141*
X0654256Y0081163*
X0654285Y0081188*
X065431Y0081217*
X0654324Y008123*
X0654339Y0081242*
X0654364Y0081271*
X0654367Y0081274*
X0654393Y0081296*
X0654418Y0081325*
X0654429Y0081335*
X0654447Y008135*
X0654472Y0081379*
X0654501Y0081404*
X0654526Y0081433*
X0654555Y0081458*
X065458Y0081487*
X0654591Y0081496*
X0654609Y0081512*
X0654634Y0081541*
X0654646Y0081551*
X0654663Y0081566*
X0654664Y0081567*
X0654688Y0081595*
X0654717Y0081621*
X0654742Y0081649*
X0654771Y0081674*
X0654796Y0081703*
X0654825Y0081729*
X065485Y0081757*
X0654879Y0081783*
X0654905Y0081811*
X0654933Y0081837*
X0654959Y0081866*
X0654987Y0081891*
X0655003Y0081908*
X0655009Y0081915*
X0655017Y0081956*
X0655034Y0082006*
X0655057Y0082053*
Y0082069*
X0655061Y0082121*
X0655071Y0082172*
X0655088Y0082222*
X0655111Y0082269*
X0655112Y008227*
Y0082285*
Y0082339*
Y0082393*
Y0082447*
Y0082501*
Y0082555*
Y0082609*
Y0082663*
Y0082717*
Y0082771*
Y0082825*
Y008288*
Y0082934*
Y0082988*
Y0083042*
Y0083096*
Y008315*
Y0083204*
Y0083258*
Y0083312*
Y0083366*
Y008342*
Y0083474*
Y0083528*
Y0083582*
Y0083636*
Y0083691*
Y0083745*
Y0083799*
Y0083853*
Y0083907*
Y0083961*
Y0084015*
Y0084069*
Y0084123*
Y0084177*
Y0084231*
Y0084285*
Y0084339*
Y0084393*
Y0084447*
Y0084501*
Y0084556*
Y008461*
Y0084664*
Y0084718*
Y0084772*
Y0084826*
Y008488*
Y0084934*
Y0084988*
Y0085042*
Y0085096*
Y008515*
Y0085204*
Y0085258*
Y0085312*
Y0085366*
Y0085421*
Y0085474*
Y0085529*
Y0085583*
Y0085637*
Y0085691*
Y0085745*
Y0085799*
Y0085853*
Y0085907*
Y0085961*
Y0086015*
Y0086069*
Y0086123*
Y0086177*
Y0086231*
Y0086286*
Y0086339*
Y0086394*
Y0086448*
Y0086502*
Y0086556*
Y008661*
Y0086664*
Y0086718*
Y0086772*
Y0086826*
Y008688*
Y0086934*
Y0086988*
Y0087042*
Y0087096*
Y0087151*
Y0087204*
Y0087259*
Y0087313*
Y0087367*
Y0087421*
Y0087475*
Y0087529*
Y0087583*
Y0087637*
Y0087691*
Y0087745*
Y0087799*
Y0087853*
Y0087907*
Y0087961*
Y0088016*
Y0088069*
Y0088124*
Y0088178*
Y0088232*
Y0088286*
Y008834*
Y0088394*
Y0088448*
Y0088502*
Y0088556*
Y008861*
Y0088664*
Y0088718*
Y0088772*
Y0088826*
Y008888*
Y0088934*
Y0088989*
Y0089043*
Y0089097*
Y0089151*
Y0089205*
Y0089259*
Y0089313*
Y0089367*
Y0089421*
Y0089475*
Y0089529*
Y0089544*
X0655111Y0089545*
X0655088Y0089592*
X0655071Y0089642*
X0655061Y0089693*
X0655057Y0089745*
Y0089761*
X0655034Y0089808*
X0655027Y0089828*
X0655013Y008984*
X0654987Y0089869*
X0654959Y0089894*
X0654933Y0089923*
X0654905Y0089949*
X0654879Y0089977*
X065485Y0090003*
X0654825Y0090031*
X0654796Y0090057*
X0654771Y0090086*
X0654742Y0090111*
X0654738Y0090116*
X0654717Y009014*
X0654688Y0090165*
X0654663Y0090194*
X0654634Y0090219*
X0654609Y0090248*
X065458Y0090273*
X065457Y0090285*
X0654555Y0090302*
X0654526Y0090327*
X0654501Y0090356*
X0654472Y0090381*
X0654447Y009041*
X0654418Y0090435*
X0654393Y0090464*
X0654364Y0090489*
X0654339Y0090518*
X065431Y0090543*
X0654285Y0090572*
X0654256Y0090597*
X065423Y0090626*
X0654202Y0090651*
X0654182Y0090673*
X0654177Y009068*
X0654148Y0090705*
X0654122Y0090734*
X0654094Y0090759*
X0654068Y0090788*
X0654039Y0090813*
X065402Y0090835*
X0654014Y0090842*
X0653986Y0090868*
X065396Y0090896*
X0653931Y0090922*
X0653906Y009095*
X0653877Y0090976*
X0653852Y0091005*
X0653823Y009103*
X0653798Y0091059*
X0653769Y0091084*
X0653744Y0091113*
X0653715Y0091138*
X065369Y0091167*
X0653661Y0091192*
X0653636Y0091221*
X0653607Y0091246*
X0653601Y0091253*
X0653582Y0091275*
X0653557Y0091296*
X0653516Y0091304*
X0653467Y0091321*
X065342Y0091344*
X0653419Y0091345*
X065335*
X0653298Y0091348*
X0653246Y0091359*
X0653196Y0091375*
X0653149Y0091399*
G37*
G36*
X0641634D02*
X0634575D01*
X0634548Y0091385*
X0634545Y0091372*
X0634528Y0091322*
X0634505Y0091275*
Y0091274*
Y0091259*
Y0091205*
Y0091151*
Y0091097*
Y0091043*
Y0090989*
Y0090935*
Y0090881*
Y0090827*
Y0090773*
Y0090719*
Y0090664*
Y009061*
Y0090556*
Y0090502*
Y0090448*
Y0090394*
Y009034*
Y0090286*
Y0090232*
Y0090178*
Y0090124*
Y009007*
Y0090016*
Y0089962*
Y0089908*
Y0089854*
Y0089799*
Y0089745*
Y0089691*
Y0089637*
Y0089583*
Y0089529*
Y0089475*
Y0089421*
Y0089367*
Y0089313*
Y0089259*
Y0089205*
Y0089151*
Y0089097*
Y0089043*
Y0088989*
Y0088934*
Y008888*
Y0088826*
Y0088772*
Y0088718*
Y0088664*
Y008861*
Y0088556*
Y0088502*
Y0088448*
Y0088394*
Y008834*
Y0088286*
Y0088232*
Y0088178*
Y0088124*
Y0088069*
Y0088016*
Y0087961*
Y0087907*
Y0087853*
Y0087799*
Y0087745*
Y0087691*
Y0087637*
Y0087583*
Y0087529*
Y0087475*
Y0087421*
Y0087367*
Y0087313*
Y0087259*
Y0087204*
Y0087151*
Y0087096*
Y0087042*
Y0086988*
Y0086934*
Y008688*
Y0086826*
Y0086772*
Y0086718*
Y0086664*
Y008661*
Y0086556*
Y0086502*
Y0086448*
Y0086394*
Y0086339*
Y0086286*
Y0086231*
Y0086177*
Y0086123*
Y0086069*
Y0086015*
Y0085961*
Y0085907*
Y0085853*
Y0085799*
Y0085745*
Y0085691*
Y0085637*
Y0085583*
Y0085529*
Y0085474*
Y0085421*
Y0085366*
Y0085312*
Y0085258*
Y0085204*
Y008515*
Y0085096*
Y0085042*
Y0084988*
Y0084934*
Y008488*
Y0084826*
Y0084772*
Y0084718*
Y0084664*
Y008461*
Y0084556*
Y0084501*
Y0084447*
Y0084393*
Y0084339*
Y0084285*
Y0084231*
Y0084177*
Y0084123*
Y0084069*
Y0084015*
Y0083961*
Y0083907*
Y0083853*
Y0083799*
Y0083745*
Y0083691*
Y0083636*
Y0083582*
Y0083528*
Y0083474*
Y008342*
Y0083366*
Y0083312*
Y0083258*
Y0083204*
Y008315*
Y0083096*
Y0083042*
Y0082988*
Y0082934*
Y008288*
Y0082825*
Y0082771*
Y0082717*
Y0082663*
Y0082609*
Y0082555*
Y0082501*
Y0082447*
Y0082393*
Y0082339*
Y0082285*
Y0082231*
Y0082177*
Y0082123*
Y0082069*
Y0082015*
Y008196*
Y0081906*
Y0081852*
Y0081798*
Y0081744*
Y008169*
Y0081636*
Y0081582*
Y0081528*
Y0081474*
Y008142*
Y0081366*
Y0081312*
Y0081258*
Y0081204*
Y008115*
Y0081095*
Y0081042*
Y0080987*
Y0080933*
Y0080879*
Y0080825*
Y0080771*
Y0080717*
Y0080663*
Y0080609*
Y0080594*
Y0080593*
X0634528Y0080546*
X0634545Y0080497*
X0634555Y0080445*
X0634557Y0080415*
X0636699*
X0636701Y0080421*
X0636707Y0080438*
X063673Y0080485*
Y0080486*
Y0080501*
Y0080555*
Y0080609*
Y0080663*
Y0080717*
Y0080771*
Y0080825*
Y0080879*
Y0080933*
Y0080987*
Y0081042*
Y0081095*
Y008115*
Y0081204*
Y0081258*
Y0081312*
Y0081366*
Y008142*
Y0081474*
Y0081528*
Y0081582*
Y0081636*
Y008169*
Y0081744*
Y0081798*
Y0081852*
Y0081906*
Y008196*
Y0082015*
Y0082069*
Y0082123*
Y0082177*
Y0082231*
Y0082285*
Y0082339*
Y0082393*
Y0082447*
Y0082501*
Y0082555*
Y0082609*
Y0082663*
Y0082717*
Y0082771*
Y0082825*
Y008288*
Y0082934*
Y0082988*
Y0083003*
X0636707Y0083051*
X063669Y00831*
X063668Y0083152*
X0636676Y0083204*
Y0083258*
X063668Y008331*
X063669Y0083362*
X0636707Y0083411*
X063673Y0083458*
Y0083459*
Y0083474*
Y0083528*
X0636734Y0083581*
X0636744Y0083632*
X0636761Y0083682*
X0636784Y0083729*
X0636813Y0083772*
X0636848Y0083812*
X0636887Y0083846*
X0636931Y0083876*
X0636978Y0083899*
X0637028Y0083916*
X0637079Y0083926*
X0637131Y0083929*
X0639186*
X0639238Y0083926*
X0639289Y0083916*
X0639339Y0083899*
X0639386Y0083876*
X063943Y0083846*
X0639469Y0083812*
X0639504Y0083772*
X0639533Y0083729*
X0639556Y0083682*
X0639566Y0083651*
X0639587Y0083621*
X063961Y0083574*
X0639617Y0083554*
X0639631Y0083542*
X0639666Y0083502*
X0639695Y0083458*
X0639718Y0083411*
X0639728Y0083381*
X0639749Y008335*
X0639772Y0083303*
X0639779Y0083284*
X0639793Y0083271*
X0639828Y0083232*
X0639857Y0083188*
X063988Y0083141*
X0639891Y0083111*
X0639911Y008308*
X0639934Y0083033*
X0639945Y0083003*
X0639965Y0082972*
X0639989Y0082925*
X0639995Y0082906*
X064001Y0082893*
X0640044Y0082853*
X0640073Y008281*
X0640097Y0082763*
X0640107Y0082732*
X0640127Y0082702*
X0640151Y0082655*
X0640157Y0082635*
X0640172Y0082622*
X0640206Y0082583*
X0640236Y0082539*
X0640259Y0082492*
X0640268Y0082466*
X0640269Y0082462*
X0640278Y0082449*
X064029Y0082431*
X0640313Y0082384*
X0640319Y0082365*
X0640334Y0082352*
X0640369Y0082313*
X0640398Y0082269*
X0640421Y0082222*
X0640431Y0082192*
X0640452Y0082161*
X0640475Y0082114*
X0640485Y0082084*
X0640506Y0082053*
X0640529Y0082006*
X0640536Y0081986*
X064055Y0081974*
X0640585Y0081934*
X0640614Y0081891*
X0640637Y0081844*
X0640648Y0081813*
X0640668Y0081783*
X0640691Y0081735*
X0640698Y0081716*
X0640712Y0081703*
X0640747Y0081664*
X0640776Y008162*
X0640799Y0081573*
X064081Y0081543*
X064083Y0081512*
X0640853Y0081465*
X064086Y0081446*
X0640875Y0081433*
X0640909Y0081394*
X0640938Y008135*
X0640962Y0081303*
X0640972Y0081273*
X0640992Y0081242*
X0641016Y0081195*
X0641022Y0081176*
X0641037Y0081163*
X0641071Y0081123*
X0641101Y008108*
X0641124Y0081033*
X0641134Y0081002*
X0641155Y0080972*
X0641178Y0080924*
X064118Y0080918*
X0641188Y0080894*
X0641192Y0080888*
X0641209Y0080863*
X0641232Y0080816*
X0641238Y0080797*
X0641253Y0080784*
X0641288Y0080745*
X0641317Y0080701*
X064134Y0080654*
X064135Y0080624*
X0641371Y0080593*
X0641394Y0080546*
X0641401Y0080527*
X0641415Y0080514*
X064144Y0080485*
X0641469Y008046*
X0641482Y0080445*
X0641502Y0080439*
X0641548Y0080415*
X0641549*
X0643809*
X0643789Y0080456*
X0643785Y0080466*
X0643779Y0080486*
X0643758Y0080517*
X0643735Y0080564*
X0643729Y0080582*
X0643728Y0080583*
X0643714Y0080596*
X0643679Y0080635*
X064365Y0080679*
X0643627Y0080726*
X0643616Y0080756*
X0643596Y0080787*
X0643573Y0080834*
X064357Y0080841*
X0643566Y0080853*
X0643551Y0080866*
X0643517Y0080906*
X0643488Y0080949*
X0643465Y0080996*
X0643454Y0081027*
X0643434Y0081057*
X064341Y0081104*
X0643408Y0081111*
X0643404Y0081124*
X0643389Y0081137*
X0643355Y0081176*
X0643326Y008122*
X0643302Y0081266*
X0643292Y0081297*
X0643271Y0081328*
X0643248Y0081375*
X0643242Y0081394*
X0643227Y0081407*
X0643193Y0081446*
X0643163Y008149*
X064314Y0081537*
X064313Y0081567*
X0643109Y0081598*
X0643086Y0081645*
X064308Y0081664*
X0643065Y0081677*
X064303Y0081717*
X0643001Y008176*
X0642978Y0081807*
X0642968Y0081837*
X0642947Y0081868*
X0642924Y0081915*
X0642922Y0081922*
X0642917Y0081934*
X0642903Y0081947*
X0642868Y0081987*
X0642839Y008203*
X0642816Y0082077*
X064281Y0082096*
X0642806Y0082108*
X0642785Y0082139*
X0642762Y0082186*
X0642755Y0082205*
X0642741Y0082218*
X0642706Y0082257*
X0642677Y0082301*
X0642654Y0082348*
X0642648Y0082366*
X0642643Y0082378*
X0642623Y0082409*
X06426Y0082456*
X0642594Y0082473*
X0642593Y0082475*
X0642578Y0082488*
X0642544Y0082527*
X0642515Y0082571*
X0642491Y0082618*
X0642486Y0082635*
X0642481Y0082648*
X0642461Y0082679*
X0642437Y0082726*
X0642431Y0082745*
X0642416Y0082758*
X0642382Y0082798*
X0642352Y0082841*
X0642329Y0082888*
X0642319Y0082919*
X0642298Y008295*
X0642275Y0082996*
X0642265Y0083027*
X0642244Y0083058*
X0642221Y0083105*
X0642215Y0083124*
X06422Y0083137*
X0642165Y0083176*
X0642136Y008322*
X0642113Y0083267*
X0642103Y0083297*
X0642082Y0083328*
X0642059Y0083375*
X0642057Y0083381*
X0642053Y0083394*
X0642038Y0083407*
X0642003Y0083447*
X0641974Y008349*
X0641951Y0083537*
X0641934Y0083587*
X0641924Y0083638*
X064192Y0083691*
Y0083745*
Y0083799*
X0641924Y0083851*
X0641934Y0083902*
X0641951Y0083952*
X0641974Y0083999*
X0642003Y0084043*
X0642038Y0084082*
X0642067Y0084107*
Y0084108*
X0642092Y0084136*
X0642121Y0084161*
X0642146Y008419*
X0642175Y0084215*
X06422Y0084244*
X0642203Y0084247*
X0642229Y0084269*
X0642254Y0084298*
X0642283Y0084324*
X0642308Y0084352*
X0642337Y0084378*
X0642362Y0084406*
X0642391Y0084432*
X0642416Y0084461*
X0642445Y0084486*
X064247Y0084515*
X0642473Y0084517*
X0642499Y008454*
X0642524Y0084569*
X0642553Y0084594*
X0642578Y0084623*
X0642607Y0084648*
X0642632Y0084677*
X0642661Y0084702*
X0642687Y0084731*
X0642697Y008474*
X0642715Y0084756*
X0642741Y0084785*
X0642769Y008481*
X0642795Y0084839*
X0642823Y0084864*
X0642849Y0084893*
X0642877Y0084918*
X0642903Y0084947*
X0642932Y0084972*
X0642957Y0085001*
X0642986Y0085026*
X0643011Y0085055*
X064304Y008508*
X0643065Y0085109*
X0643094Y0085135*
X0643119Y0085163*
X0643148Y0085189*
X0643173Y0085217*
X064318Y0085223*
X0643188Y008523*
X0643194Y008525*
X0643218Y0085296*
X0643247Y008534*
X0643281Y008538*
X0643284Y0085382*
X064331Y0085405*
X0643335Y0085434*
X0643346Y0085443*
X0643364Y0085459*
X0643389Y0085488*
X0643396Y0085493*
X0643418Y0085513*
X0643443Y0085542*
X0643454Y0085551*
X0643472Y0085567*
X0643497Y0085596*
X0643501Y0085598*
X0643512Y0085609*
X0643519Y0085628*
X0643542Y0085675*
X064356Y0085702*
X0643562Y0085706*
X0643573Y0085736*
X0643596Y0085783*
Y0085784*
Y0085799*
Y0085853*
Y0085907*
Y0085961*
Y0086015*
Y0086069*
Y0086123*
Y0086177*
Y0086231*
Y0086286*
Y0086339*
Y0086394*
Y0086448*
Y0086502*
Y0086556*
Y008661*
Y0086664*
Y0086718*
Y0086772*
Y0086826*
Y008688*
Y0086934*
Y0086988*
Y0087042*
Y0087096*
Y0087151*
Y0087204*
Y0087259*
Y0087313*
Y0087367*
Y0087421*
Y0087475*
Y0087529*
Y0087583*
Y0087637*
Y0087691*
Y0087745*
Y0087799*
Y0087853*
Y0087907*
Y0087961*
Y0088016*
Y0088069*
Y0088124*
Y0088178*
Y0088232*
Y0088286*
Y008834*
Y0088394*
Y0088448*
Y0088502*
Y0088556*
Y008861*
Y0088664*
Y0088718*
Y0088772*
Y0088826*
Y008888*
Y0088934*
Y0088989*
Y0089043*
Y0089097*
Y0089151*
Y0089205*
Y0089259*
Y0089313*
Y0089367*
Y0089421*
Y0089475*
Y0089529*
Y0089583*
Y0089637*
Y0089653*
X0643573Y00897*
X0643556Y008975*
X0643546Y0089801*
X0643545Y0089811*
X0643542Y0089815*
X0643519Y0089862*
X0643512Y0089882*
X0643497Y0089894*
X0643472Y0089923*
X0643443Y0089949*
X0643424Y008997*
X0643418Y0089977*
X0643389Y0090003*
X0643364Y0090031*
X0643335Y0090057*
X064331Y0090086*
X0643281Y0090111*
X0643264Y009013*
X0643256Y009014*
X0643227Y0090165*
X0643202Y0090194*
X0643173Y0090219*
X0643148Y0090248*
X0643119Y0090273*
X0643109Y0090285*
X0643094Y0090302*
X0643065Y0090327*
X064304Y0090356*
X0643011Y0090381*
X0642986Y009041*
X0642957Y0090435*
X0642932Y0090464*
X0642903Y0090489*
X0642886Y0090509*
X0642877Y0090518*
X0642849Y0090543*
X0642823Y0090572*
X0642795Y0090597*
X0642769Y0090626*
X0642741Y0090651*
X0642715Y009068*
X0642687Y0090705*
X0642661Y0090734*
X0642632Y0090759*
X0642607Y0090788*
X0642578Y0090813*
X0642553Y0090842*
X0642524Y0090868*
X0642499Y0090896*
X064247Y0090922*
X0642445Y0090951*
X0642416Y0090976*
X0642391Y0091005*
X0642362Y009103*
X0642337Y0091059*
X0642308Y0091084*
X0642283Y0091113*
X0642254Y0091138*
X0642229Y0091167*
X06422Y0091192*
X0642175Y0091221*
X0642146Y0091246*
X0642133Y0091261*
X0642114Y0091267*
X0642067Y009129*
X0642062Y0091294*
X0642053*
X0642001Y0091304*
X0641952Y0091321*
X0641904Y0091344*
Y0091345*
X0641835*
X0641782Y0091348*
X0641731Y0091359*
X0641681Y0091375*
X0641634Y0091399*
G37*
%LNtimecard-dc-beta-v1-3*%
%LPD*%
G36*
X0652483Y0089332D02*
X0652535Y0089322D01*
X0652584Y0089305*
X0652631Y0089282*
X0652662Y0089261*
X0652692Y0089251*
X0652739Y0089228*
X0652783Y0089198*
X0652822Y0089164*
X0652857Y0089125*
X0652886Y0089081*
X0652909Y0089034*
X0652926Y0088984*
X0652936Y0088933*
X065294Y008888*
Y0088826*
Y0088772*
Y0088718*
Y0088664*
Y008861*
Y0088556*
Y0088502*
Y0088448*
Y0088394*
Y008834*
Y0088286*
Y0088232*
Y0088178*
Y0088124*
Y0088069*
Y0088016*
Y0087961*
Y0087907*
Y0087853*
Y0087799*
Y0087745*
Y0087691*
Y0087637*
Y0087583*
Y0087529*
Y0087475*
Y0087421*
Y0087367*
Y0087313*
Y0087259*
Y0087204*
Y0087151*
Y0087096*
Y0087042*
Y0086988*
Y0086934*
Y008688*
Y0086826*
Y0086772*
Y0086718*
Y0086664*
Y008661*
Y0086556*
Y0086502*
Y0086448*
Y0086394*
Y0086339*
Y0086286*
Y0086231*
Y0086177*
Y0086123*
Y0086069*
Y0086015*
Y0085961*
Y0085907*
Y0085853*
Y0085799*
Y0085745*
Y0085691*
Y0085637*
Y0085583*
Y0085529*
Y0085474*
Y0085421*
Y0085366*
Y0085312*
Y0085258*
Y0085204*
Y008515*
Y0085096*
Y0085042*
Y0084988*
Y0084934*
Y008488*
Y0084826*
Y0084772*
Y0084718*
Y0084664*
Y008461*
Y0084556*
Y0084501*
Y0084447*
Y0084393*
Y0084339*
Y0084285*
Y0084231*
Y0084177*
Y0084123*
Y0084069*
Y0084015*
Y0083961*
Y0083907*
Y0083853*
Y0083799*
Y0083745*
Y0083691*
Y0083636*
Y0083582*
Y0083528*
Y0083474*
Y008342*
Y0083366*
Y0083312*
Y0083258*
Y0083204*
Y008315*
Y0083096*
Y0083042*
Y0082988*
Y0082934*
Y008288*
X0652936Y0082827*
X0652926Y0082776*
X0652909Y0082726*
X0652886Y0082679*
X0652857Y0082635*
X0652822Y0082596*
X0652783Y0082561*
X0652739Y0082532*
X0652692Y0082509*
X0652643Y0082492*
X0652591Y0082482*
X0652539Y0082479*
X0648592*
X064854Y0082482*
X0648489Y0082492*
X0648439Y0082509*
X0648392Y0082532*
X0648348Y0082561*
X0648309Y0082596*
X0648274Y0082635*
X0648245Y0082679*
X0648222Y0082726*
X0648205Y0082776*
X0648195Y0082827*
X0648191Y008288*
Y0082934*
Y0082988*
Y0083042*
Y0083096*
Y008315*
Y0083204*
Y0083258*
Y0083312*
Y0083366*
Y008342*
Y0083474*
Y0083528*
Y0083582*
Y0083636*
Y0083691*
Y0083745*
Y0083799*
Y0083853*
Y0083907*
Y0083961*
Y0084015*
Y0084069*
Y0084123*
Y0084177*
Y0084231*
Y0084285*
Y0084339*
Y0084393*
Y0084447*
Y0084501*
Y0084556*
Y008461*
Y0084664*
Y0084718*
Y0084772*
Y0084826*
Y008488*
Y0084934*
Y0084988*
Y0085042*
Y0085096*
Y008515*
Y0085204*
Y0085258*
Y0085312*
Y0085366*
Y0085421*
Y0085474*
Y0085529*
Y0085583*
Y0085637*
Y0085691*
Y0085745*
Y0085799*
Y0085853*
Y0085907*
Y0085961*
Y0086015*
Y0086069*
Y0086123*
Y0086177*
Y0086231*
Y0086286*
Y0086339*
Y0086394*
Y0086448*
Y0086502*
Y0086556*
Y008661*
Y0086664*
Y0086718*
Y0086772*
Y0086826*
Y008688*
Y0086934*
Y0086988*
Y0087042*
Y0087096*
Y0087151*
Y0087204*
Y0087259*
Y0087313*
Y0087367*
Y0087421*
Y0087475*
Y0087529*
Y0087583*
Y0087637*
Y0087691*
Y0087745*
Y0087799*
Y0087853*
Y0087907*
Y0087961*
Y0088016*
Y0088069*
Y0088124*
Y0088178*
Y0088232*
Y0088286*
Y008834*
Y0088394*
Y0088448*
Y0088502*
Y0088556*
Y008861*
Y0088664*
Y0088718*
Y0088772*
Y0088826*
Y008888*
X0648195Y0088933*
X0648205Y0088984*
X0648222Y0089034*
X0648245Y0089081*
X0648274Y0089125*
X0648309Y0089164*
X0648326Y0089179*
X0648338Y0089189*
X0648363Y0089218*
X0648402Y0089253*
X0648446Y0089282*
X0648493Y0089305*
X0648543Y0089322*
X0648594Y0089332*
X0648646Y0089335*
X0648701*
X0648753Y0089332*
X0648804Y0089322*
X0648854Y0089305*
X0648901Y0089282*
X0648902Y0089281*
X0652014*
Y0089282*
X0652061Y0089305*
X0652111Y0089322*
X0652162Y0089332*
X0652214Y0089335*
X0652269*
X0652321Y0089332*
X0652323*
X0652324*
X0652377Y0089335*
X0652431*
X0652483Y0089332*
G37*
G36*
X0641076Y008944D02*
X0641127Y008943D01*
X0641177Y0089413*
X0641224Y008939*
X0641268Y0089361*
X0641307Y0089326*
X0641342Y0089287*
X0641371Y0089243*
X0641394Y0089196*
X0641411Y0089146*
X0641421Y0089095*
X0641425Y0089043*
Y0088989*
Y0088934*
Y008888*
Y0088826*
Y0088772*
Y0088718*
Y0088664*
Y008861*
Y0088556*
Y0088502*
Y0088448*
Y0088394*
Y008834*
Y0088286*
Y0088232*
Y0088178*
Y0088124*
Y0088069*
Y0088016*
Y0087961*
Y0087907*
Y0087853*
Y0087799*
Y0087745*
Y0087691*
Y0087637*
Y0087583*
Y0087529*
Y0087475*
Y0087421*
Y0087367*
Y0087313*
Y0087259*
Y0087204*
Y0087151*
Y0087096*
Y0087042*
Y0086988*
Y0086934*
Y008688*
Y0086826*
Y0086772*
Y0086718*
Y0086664*
Y008661*
Y0086556*
Y0086502*
Y0086448*
Y0086394*
Y0086339*
Y0086286*
Y0086231*
Y0086177*
X0641421Y0086125*
X0641411Y0086074*
X0641394Y0086024*
X0641371Y0085977*
X0641342Y0085933*
X0641307Y0085894*
X0641268Y0085859*
X0641224Y008583*
X0641177Y0085807*
X0641127Y008579*
X0641076Y008578*
X0641024Y0085777*
X0636969*
X0636917Y008578*
X0636865Y008579*
X0636816Y0085807*
X0636769Y008583*
X0636725Y0085859*
X0636686Y0085894*
X0636651Y0085933*
X0636622Y0085977*
X0636599Y0086024*
X0636582Y0086074*
X0636572Y0086125*
X0636568Y0086177*
Y0086231*
Y0086286*
Y0086339*
Y0086394*
Y0086448*
Y0086502*
Y0086556*
Y008661*
Y0086664*
Y0086718*
Y0086772*
Y0086826*
Y008688*
Y0086934*
Y0086988*
Y0087042*
Y0087096*
Y0087151*
Y0087204*
Y0087259*
Y0087313*
Y0087367*
Y0087421*
Y0087475*
Y0087529*
Y0087583*
Y0087637*
Y0087691*
Y0087745*
Y0087799*
Y0087853*
Y0087907*
Y0087961*
Y0088016*
Y0088069*
Y0088124*
Y0088178*
Y0088232*
Y0088286*
Y008834*
Y0088394*
Y0088448*
Y0088502*
Y0088556*
Y008861*
Y0088664*
Y0088718*
Y0088772*
Y0088826*
Y008888*
Y0088934*
Y0088989*
Y0089043*
X0636572Y0089095*
X0636582Y0089146*
X0636599Y0089196*
X0636622Y0089243*
X0636651Y0089287*
X0636686Y0089326*
X0636725Y0089361*
X0636769Y008939*
X0636816Y0089413*
X0636865Y008943*
X0636917Y008944*
X0636969Y0089443*
X0641024*
X0641076Y008944*
G37*
G54D23*
X0113976Y0152362D03*
Y0144882D03*
X0104528D03*
Y0148622D03*
Y0152362D03*
X0104331Y0100394D03*
Y0096653D03*
Y0092913D03*
X0113779D03*
Y0100394D03*
X0114961Y024626D03*
Y025D03*
Y025374D03*
X0105512D03*
Y024626D03*
X0114961Y019311D03*
Y019685D03*
Y0200591D03*
X0105512D03*
Y019311D03*
G54D51*
X0318848Y0285433D03*
Y0283465D03*
Y0281496D03*
Y0279528D03*
X0328789D03*
Y0281496D03*
Y0283465D03*
Y0285433D03*
G54D52*
X032185Y0278494D03*
X0323819D03*
X0325787D03*
Y0286467D03*
X0323819D03*
X032185D03*
G54D53*
X0357382Y0281201D03*
Y0278642D03*
X0349311D03*
Y0281201D03*
Y028376D03*
Y0286319D03*
X0357382D03*
Y028376D03*
G54D54*
X0301969Y0277298D03*
X0294488D03*
Y0285694D03*
X0298228D03*
G54D55*
X0301969Y0285694D03*
G54D63*
X0147047Y0024508D03*
G54D64*
X0244685Y0011122D03*
G54D65*
X0106693Y0161417D03*
X0112205D03*
X0631496Y0274016D03*
X0637008D03*
X0631496Y0253543D03*
X0637008D03*
X0631496Y026063D03*
X0637008D03*
X0631496Y0267323D03*
X0637008D03*
X066874Y0161106D03*
X0663228D03*
X066874Y0167106D03*
X0663228D03*
X066874Y0172106D03*
X0663228D03*
X066874Y0177606D03*
X0663228D03*
X0684728Y0209606D03*
X069024D03*
X061524Y0217106D03*
X0609728D03*
X0361516Y0064567D03*
X0356004D03*
X0519882Y0292323D03*
X0525394D03*
X010748Y0237205D03*
X0112992D03*
X010748Y0184055D03*
X0112992D03*
X0111811Y0110433D03*
X0106299D03*
X0356299Y0295276D03*
X0350787D03*
X0324803Y0269685D03*
X0319291D03*
G54D66*
X0052165Y0112795D03*
X0052362Y0218701D03*
G54D67*
X0058858Y0112795D03*
Y0121457D03*
X0051378D03*
X0059055Y0218701D03*
Y0227362D03*
X0051575D03*
G54D68*
X0052559Y0084744D03*
Y0096358D03*
Y0189469D03*
Y0201083D03*
Y0242224D03*
Y0253839D03*
Y01375D03*
Y0149114D03*
G54D69*
X0058563Y0090551D03*
Y0195276D03*
Y0248031D03*
Y0143307D03*
G54D70*
X0213583Y0357677D03*
Y0362795D03*
X0204724Y0360236D03*
X0159941Y0357677D03*
Y0362795D03*
X0151083Y0360236D03*
X0177657Y0357677D03*
Y0362795D03*
X0168799Y0360236D03*
X0195866Y0357677D03*
Y0362795D03*
X0187008Y0360236D03*
G54D71*
X061574Y0224106D03*
Y0229106D03*
Y0234106D03*
Y0239106D03*
X0635228D03*
Y0234106D03*
Y0229106D03*
Y0224106D03*
X0683228Y0203106D03*
Y0198106D03*
Y0193106D03*
Y0188106D03*
X066374D03*
Y0193106D03*
Y0198106D03*
Y0203106D03*
G54D72*
X0185827Y0067421D03*
Y0053051D03*
G54D73*
X020161Y0422114D03*
Y0395106D03*
X019161Y0422114D03*
Y0395106D03*
X018161Y0422114D03*
Y0395106D03*
X017161Y0422114D03*
Y0395106D03*
X016161Y0422114D03*
Y0395106D03*
G54D74*
X0407805Y0176893D03*
X0392057D03*
X0407805Y0174893D03*
X0392057D03*
X0407805Y0172893D03*
X0392057D03*
X0407805Y0170893D03*
X0392057D03*
X0407805Y0168893D03*
X0392057D03*
X0407805Y0166893D03*
X0392057D03*
X0407805Y0164893D03*
X0392057D03*
X0407805Y0162893D03*
X0392057D03*
X0407805Y0160893D03*
X0392057D03*
Y0158893D03*
X0407805D03*
G54D75*
X0201772Y0378937D03*
Y0371063D03*
X0161417Y0378937D03*
Y0371063D03*
X017126Y0378937D03*
Y0371063D03*
X0181102Y0378937D03*
Y0371063D03*
G54D76*
X0455709Y0284941D03*
Y0289862D03*
X0064173Y0405217D03*
Y0410532D03*
X0084646Y0405217D03*
Y0410532D03*
X0104724Y0405217D03*
Y0410532D03*
X0124803Y0405217D03*
Y0410532D03*
G54D77*
X0237205Y0272638D03*
Y0278543D03*
X024311Y0272638D03*
Y0278543D03*
G54D78*
X0298524Y0269685D03*
X0293996D03*
G54D79*
X0097441Y025374D03*
Y0248228D03*
Y0142913D03*
Y0148425D03*
X049311Y027874D03*
Y0284252D03*
X0097441Y0196063D03*
Y0201575D03*
Y0090748D03*
Y009626D03*
G54D80*
X0523228Y0277559D03*
X051811D03*
X0523228Y0285433D03*
X051811D03*
G54D81*
X0612284Y024339D03*
Y0248823D03*
X0194488Y0067244D03*
Y0061811D03*
X0612992Y0280748D03*
Y0286181D03*
X0674984Y020889D03*
Y0214323D03*
X0623484Y021289D03*
Y0218323D03*
X07Y0187835D03*
Y0193268D03*
X0600394Y0233504D03*
Y0238937D03*
G54D82*
X0305512Y0057382D03*
Y0060728D03*
X0250394Y0057382D03*
Y0060728D03*
G54D83*
X0309646Y001378D03*
X0187599D03*
X0183661D03*
X0179725D03*
X0207283D03*
X025059D03*
X0293898D03*
X0289961D03*
X027815D03*
X0274213D03*
X0262402D03*
X0258465D03*
X0242717D03*
X0238779D03*
X0215158D03*
X0211221D03*
X0230906D03*
X0301771D03*
X0195473D03*
X0199409D03*
X0219094D03*
X0297834D03*
X0286023D03*
X0270275D03*
X0266338D03*
X0203346D03*
X0191535D03*
X0282086D03*
X0234842D03*
X0246654D03*
X0254527D03*
G54D84*
X0305709Y001573D03*
G54D85*
X0535433Y0290433D03*
Y0285433D03*
Y0280433D03*
Y0275433D03*
X0554331Y0290433D03*
Y0285433D03*
Y0280433D03*
Y0275433D03*
G54D86*
X0465158Y028998D03*
Y028498D03*
Y027998D03*
Y027498D03*
X0483661Y028998D03*
Y028498D03*
Y027998D03*
Y027498D03*
G54D87*
X0667984Y0242012D03*
Y0280201D03*
X0631984Y0146012D03*
Y0184201D03*
G54D88*
X0263779Y0362205D03*
Y0354331D03*
Y0346457D03*
Y0338583D03*
X024628Y0362205D03*
Y0346457D03*
Y0354331D03*
Y0338583D03*
G54D89*
X0221259Y0103817D03*
X029803Y0235868D03*
X0258661Y0251812D03*
X0248817D03*
X0238976D03*
X0229133D03*
X0288188Y0235868D03*
X0278345D03*
X0268502D03*
X0258661D03*
X0248817D03*
X0238976D03*
X0229133D03*
X0294093D03*
X0296061D03*
X0290157D03*
X0292125D03*
X028425D03*
X028622D03*
X0280313D03*
X0282282D03*
X0274409D03*
X0276377D03*
X0254724D03*
X0256692D03*
X0250786D03*
X0235038D03*
X0237006D03*
X0221258Y0251812D03*
X0223228D03*
Y0235868D03*
X0221258D03*
X0225196Y0251812D03*
X0227165D03*
X0240944D03*
X0242913D03*
X0235038D03*
X0237006D03*
X0250786D03*
X0252754D03*
X0244881D03*
X0246849D03*
X0260629D03*
X0254724D03*
X0262597D03*
X0256692D03*
X0225196Y0235868D03*
X0231101D03*
X0233069D03*
X0227165D03*
X0231101Y0251812D03*
X0233069D03*
X0280314Y0103817D03*
X0282283D03*
X0286221Y0087874D03*
X0288189D03*
X027441D03*
X0276378D03*
X0268503Y0103817D03*
X0270473D03*
X0258662Y0087874D03*
Y0103817D03*
X0264566Y0087874D03*
X0262598D03*
X027441Y0103817D03*
X0276378D03*
X0280314Y0087874D03*
X0282283D03*
X0268503D03*
X0270473D03*
X0262598Y0103817D03*
X0264566D03*
X0223229Y0087874D03*
X0242914D03*
X0237007D03*
X0235039D03*
X023307D03*
X0229134D03*
X0238977D03*
X0248818D03*
X0252755D03*
X0254725D03*
X0256693D03*
X0244882D03*
X024685D03*
X0225197D03*
X0227166D03*
X0256693Y0103817D03*
X0237007D03*
X0238977D03*
X0242914D03*
X024685D03*
X0248818D03*
X0244882D03*
X0229134D03*
X0227166D03*
X0225197D03*
X0223229D03*
X0235039D03*
X023307D03*
X0254725D03*
X0252755D03*
X0286221D03*
X0288189D03*
X0292126Y0087874D03*
Y0103817D03*
X0294094Y0087874D03*
Y0103817D03*
X0298031Y0087874D03*
Y0103817D03*
X0296062D03*
Y0087874D03*
X0290158Y0103817D03*
X0284251D03*
X0278346D03*
X0272441D03*
X0266535D03*
X026063D03*
X0250787D03*
X0240945D03*
X0231102D03*
X0290158Y0087874D03*
X0284251D03*
X0278346D03*
X0272441D03*
X0266535D03*
X026063D03*
X0250787D03*
X0240945D03*
X0231102D03*
X0221259D03*
X0264565Y0251812D03*
X0266534D03*
X0268502D03*
X0270472D03*
X027244D03*
X0274409D03*
X0276377D03*
X0278345D03*
X0280313D03*
X0282282D03*
X028425D03*
X028622D03*
X0288188D03*
X0290157D03*
X0292125D03*
X0294093D03*
X0296061D03*
X029803D03*
X0262597Y0235868D03*
X0266534D03*
X027244D03*
X0246849D03*
X0244881D03*
X0242913D03*
X0240944D03*
X0252754D03*
X0270472D03*
X0264565D03*
X0260629D03*
G54D90*
X0169689Y0126339D03*
X0357091D03*
X0169689Y0214331D03*
X0357091D03*
G54D91*
X0215654Y0243858D03*
Y0095827D03*
X0303646D03*
Y0243858D03*
G54D92*
X0349164Y0139823D03*
Y0137856D03*
Y0145729D03*
Y0147697D03*
Y0177225D03*
Y0149667D03*
Y0179193D03*
Y0189037D03*
Y0185099D03*
Y0187067D03*
Y0183131D03*
X0365107Y0187067D03*
Y0189037D03*
Y0192973D03*
X0349164Y0133918D03*
Y0135887D03*
X0365107Y0179193D03*
Y0177225D03*
Y0185099D03*
Y0183131D03*
Y0194941D03*
Y0198879D03*
Y0196911D03*
X0349164Y0198879D03*
Y0196911D03*
X0365107Y0169351D03*
X0349164Y0163445D03*
Y0167383D03*
Y0165415D03*
Y0169351D03*
X0365107Y0173289D03*
Y0175257D03*
Y0165415D03*
Y0157541D03*
Y0155571D03*
Y0167383D03*
Y0163445D03*
X0349164Y0192973D03*
Y0155571D03*
Y0200848D03*
Y0191005D03*
Y0181163D03*
Y0171319D03*
Y0161477D03*
Y0151635D03*
Y0141793D03*
X0365107Y0200848D03*
Y0191005D03*
Y0181163D03*
Y0171319D03*
Y0161477D03*
Y0151635D03*
Y0141793D03*
X0349164Y0194941D03*
X0365107Y0159509D03*
X0349164Y0153603D03*
X0365107Y0149667D03*
Y0147697D03*
Y0145729D03*
Y0143761D03*
Y0139823D03*
Y0137856D03*
Y0135887D03*
Y0133918D03*
X0349164Y0131949D03*
X0365107D03*
X0349164Y0173289D03*
Y0175257D03*
X0365107Y0153603D03*
X0349164Y0157541D03*
Y0159509D03*
Y0143761D03*
Y0208721D03*
Y0206752D03*
Y0204784D03*
Y0202816D03*
X0365107Y0208721D03*
Y0206752D03*
Y0204784D03*
Y0202816D03*
X0177617Y016345D03*
Y0161481D03*
Y0187072D03*
Y0202819D03*
Y0191008D03*
Y0183134D03*
Y0194946D03*
Y0173293D03*
Y0177229D03*
X0161672Y0192977D03*
Y0185103D03*
Y0191008D03*
Y0202819D03*
X0177617Y0200851D03*
Y0196915D03*
Y0145733D03*
Y0167386D03*
X0161672Y0187072D03*
Y0196915D03*
X0177617Y0192977D03*
Y0185103D03*
Y0181167D03*
Y0165419D03*
X0161672Y0200851D03*
X0177617Y017526D03*
Y0171324D03*
X0161672Y0194946D03*
X0177617Y0155576D03*
Y0157545D03*
X0161672Y0151638D03*
Y0145733D03*
Y0181167D03*
Y0183134D03*
X0177617Y0143764D03*
X0161672Y013589D03*
X0177617Y0133923D03*
X0161672Y0157545D03*
Y0143764D03*
Y0153607D03*
Y0155576D03*
Y0161481D03*
Y0173293D03*
Y0167386D03*
Y0137859D03*
Y0147702D03*
Y0141797D03*
Y017526D03*
X0177617Y013589D03*
X0161672Y0133923D03*
Y016345D03*
Y0177229D03*
X0177617Y0137859D03*
Y0131954D03*
Y0141797D03*
X0161672Y0131954D03*
X0177617Y0147702D03*
X0161672Y0171324D03*
Y0165419D03*
X0177617Y0151638D03*
X0161672Y0204788D03*
X0177617D03*
Y0139828D03*
Y0149671D03*
Y0159512D03*
Y0169355D03*
Y0179198D03*
Y0189041D03*
Y0198882D03*
X0161672Y0139828D03*
Y0149671D03*
Y0159512D03*
Y0169355D03*
Y0179198D03*
Y0189041D03*
Y0198882D03*
Y0208726D03*
X0177617D03*
Y0206756D03*
Y0153607D03*
X0161672Y0206756D03*
G54D93*
X0124984Y0419752D03*
Y0425461D03*
X0619291Y0282185D03*
Y0287894D03*
X0064484Y0425461D03*
Y0419752D03*
X0084651Y0425461D03*
Y0419752D03*
X0104818D03*
Y0425461D03*
G54D94*
X0355409Y0072606D03*
X0362496D03*
X0670028Y0142106D03*
X0662941D03*
X0670028Y0153106D03*
X0662941D03*
G54D95*
X0606484Y0238764D03*
Y0233449D03*
X0693984Y0187949D03*
Y0193264D03*
G54D96*
X0337598Y0269685D03*
Y0275197D03*
X021063Y0062992D03*
Y0068504D03*
X0286417Y0338386D03*
Y0332874D03*
X0270669Y0319685D03*
Y0314173D03*
X0285433Y027874D03*
Y0284252D03*
X05Y0289173D03*
Y0283661D03*
X0366142Y0295276D03*
Y0289764D03*
G54D97*
X0651984Y0201756D03*
Y0195457D03*
X0646984Y0230256D03*
Y0223957D03*
G54D98*
X0201969Y0062992D03*
Y0070079D03*
X0633484Y021815D03*
Y0211063D03*
X0665984Y0209563D03*
Y021665D03*
X0627559Y0282283D03*
Y028937D03*
X0636221Y0282283D03*
Y028937D03*
X0295276Y0332677D03*
Y0339764D03*
X0261811Y0321457D03*
Y031437D03*
G54D99*
X0684268Y0181606D03*
X0689701D03*
X0673661Y018189D03*
X0679095D03*
X0631142Y0246063D03*
X0636575D03*
X0139252Y0151575D03*
X0144685D03*
G54D100*
X019661Y040861D03*
X016661D03*
G54D101*
X0430778Y0258465D03*
X0418966D03*
X0407156D03*
X0398888Y0087992D03*
Y0247835D03*
X055873D03*
Y0167913D03*
Y0087992D03*
G54D102*
X0513622Y0426181D03*
G54D103*
X0523622Y0426181D03*
X0533622D03*
X0543622D03*
G54D104*
X025503Y034252D03*
Y0358268D03*
G54D105*
X0299014Y024384D03*
X0357136Y0209705D03*
Y0130965D03*
X0220274Y024384D03*
X0169644Y013097D03*
Y020971D03*
X0220275Y0095846D03*
X0299015D03*
G54D106*
X0361755Y0248616D03*
X0165255Y0091615D03*
X0165155Y0248616D03*
X0361755Y0091615D03*
G54D107*
X0009984Y0258106D03*
Y0238106D03*
X0029984D03*
Y0258106D03*
X0009984Y0100606D03*
Y0080606D03*
X0029984D03*
Y0100606D03*
X0009984Y0153106D03*
Y0133106D03*
X0029984D03*
Y0153106D03*
X0009984Y0205606D03*
Y0185606D03*
X0029984D03*
Y0205606D03*
G54D108*
X0019984Y0248106D03*
Y0090606D03*
Y0143106D03*
Y0195606D03*
G54D109*
X0028543Y0415206D03*
Y0036811D03*
G54D110*
X0244124Y0317303D03*
X0482313Y0419665D03*
Y0317303D03*
X0244124Y0419665D03*
G54D111*
X0370669Y0072933D03*
M02*